FILE_TYPE = MULTI_PHYS_TABLE;

PART 'CAPACITOR'
CLASS=DISCRETE

{========================================================================================}
:CLS_PN           | VALUE     | TOLERANCE    = JEDEC_TYPE                 | ALT_SYMBOLS                                     | DESCRIPTION                                                                       | CPN_STATUS ;
{========================================================================================}
 'CL100512A'      | '10PF'    | '5%'         = 'SMC_0603R'                | '(SMC_0603R)'                                   | 'CAPACITOR,10PF,FIXED,CERAMIC,C0G,5%,50V,-55/125C,SMD,0603'                       | 'NFND'    
 'CL100513A'      | '15PF'    | '5%'         = 'SMC_0603R'                | '(SMC_0603R)'                                   | 'CAPACITOR,15PF,FIXED,CERAMIC,C0G,5%,50V,-55/125C,SMD,0603'                       | 'NFND'    
 'CL100514A'      | '1PF'     | '0.25PF'     = 'SMC_0603R'                | 'SMC_0603R'                                     | 'CAPACITOR,1PF,FIXED,CERAMIC MULTILAYER,C0G,.25 PF,50V,-55/125C,0603'             | 'NFND'    
 'CL100515A'      | '33PF'    | '5%'         = 'SMC_0603R'                | '(SMC_0603R)'                                   | 'CAPACITOR,33PF,FIXED,CERAMIC,COG,5%,50V,-55/125C,SMD,0603'                       | 'NFND'    
 'CL100516A'      | '39PF'    | '5%'         = 'SMC_0603R'                | '(SMC_0603R)'                                   | 'CAPACITOR,39PF,FIXED,CERAMIC,C0G/NPO,5%,50V,SMD,0603'                            | 'NFND'    
 'CL100517A'      | '1000PF'  | '10%'        = 'SMC_0603R'                | '(SMC_0603R)'                                   | 'CAPACITOR,1000PF,FIXED,CERAMIC,X7R,10%,50V,SMD,0603'                             | 'NFND'    
 'G101-00010-01'  | '1000PF'  | '10%'        = 'SMC_0603R'                | '(SMC_0603R)'                                   | 'CAPACITOR,1000PF,FIXED,CERAMIC,X7R,10%,50V,SMD,0603'                             | 'NFND'    
 'CL100520A'      | '470PF'   | '10%'        = 'SMC_0603R'                | '(SMC_0603R)'                                   | 'CAPACITOR,470PF,FIXED,CERAMIC,X7R,10%,50V,SMD,0603'                              | 'NFND'    
 'CL100521A'      | '100PF'   | '5%'         = 'SMC_0805R'                | '(SMC_0805R)'                                   | 'CAPACITOR,100PF,FIXED,CERAMIC,COG/NPO,5%,50V,-55/125C,SMD,0805'                  | 'NFND'    
 'CL100522A'      | '1000PF'  | '5%'         = 'SMC_0805R'                | '(SMC_0805R)'                                   | 'CAPACITOR,1000PF,FIXED,CERAMIC,COG,5%,50V,-55/125C,SMD,0805'                     | 'NFND'    
 'CL100523A'      | '27PF'    | '5%'         = 'SMC_0805R'                | '(SMC_0805R)'                                   | 'CAPACITOR,27PF,FIXED,CERAMIC,COG,5%,50V,-55/125C,SMD,0805'                       | 'NFND'    
 'CL100524A'      | '33PF'    | '5%'         = 'SMC_0805R'                | '(SMC_0805R)'                                   | 'CAPACITOR,33PF,FIXED,CERAMIC,COG,5%,50V,-55/125C,SMD,0805'                       | 'NFND'    
 'CL100525A'      | '47PF'    | '5%'         = ''                         | ''                                              | 'CAPACITOR,47PF,FIXED,CERAMIC,C0G,5%,50V,0805'                                    | 'NFND'    
 'CL100526A'      | '470PF'   | '5%'         = ''                         | ''                                              | 'CAPACITOR,470PF,FIXED,CERAMIC,C0G,5%,50V,0805'                                   | 'NFND'    
 'CL100527A'      | '0.1UF'   | '10%'        = 'SMC_0805R'                | '(SMC_0805R)'                                   | 'CAPACITOR,0.1UF,FIXED,CERAMIC MULTI LAYER,X7R,10%,50V,-55/125C,0805'             | 'NFND'    
 'CL100528A'      | '0.47UF'  | '10%'        = 'SMC_1206R'                | '(SMC_1206R)'                                   | 'CAPACITOR,0.47UF,FIXED,CERAMIC,X7R,10%,16V,-55/125C,1206'                        | 'NFND'    
 'CL100529A'      | '0.15UF'  | '10%'        = 'SMC_1206R'                | '(SMC_1206R)'                                   | 'CAPACITOR,0.15UF,FIXED,CERAMIC MULTI LAYER,X7R,10%%,50V,-55/125C,1206'           | 'NFND'    
 'CL100530A'      | '180PF'   | '5%'         = 'SMC_0402R'                | '(SMC_0402R_C)'                                 | 'CAP,180PF,5%,50V,C0G,0402'                                                       | 'NFND'    
 'CL100531A'      | '470PF'   | '5%'         = 'SMC_0402R'                | '(SMC_0402R_C)'                                 | 'CAP,470PF,5%,50V,C0G,0402'                                                       | 'NFND'    
 'CL100532A'      | '1000PF'  | '10%'        = 'SMC_0402R'                | '(SMC_0402R_C)'                                 | 'CAP,1000PF,10%,50V,X7R,0402'                                                     | 'NFND'    
 'G105-0B102-FK'  | '1000PF'  | '10%'        = 'SMC_0402R'                | '(SMC_0402R_C)'                                 | 'CAP,1000PF,10%,50V,X7R,0402'                                                     | 'NFND'    
 'CL100534A'      | '1.0UF'   | '10%'        = 'SMC_0603R'                | '(SMC_0603R)'                                   | 'CAP,1.0UF,10%,6.3V,X5R,0603'                                                     | 'NFND'    
 'CL100536A'      | '100PF'   | '5%'         = 'SMC_0603R'                | '(SMC_0603R)'                                   | 'CAP,100PF,5%,50V,COG,0603'                                                       | 'NFND'    
 'G101-00006-01'  | '100PF'   | '5%'         = 'SMC_0603R'                | '(SMC_0603R)'                                   | 'CAP,100PF,5%,50V,COG,0603'                                                       | 'NFND'    
 'CL100538A'      | '22PF'    | '5%'         = 'SMC_0603R'                | '(SMC_0603R)'                                   | 'CAP,22PF,5%,50V,C0G,CER,0603'                                                    | 'NFND'    
 'CL100539A'      | '220PF'   | '5%'         = 'SMC_0603R'                | '(SMC_0603R)'                                   | 'CAP,220PF,5%,50V,C0G,0603'                                                       | 'NFND'    
 'G106-0A221-FJ'  | '220PF'   | '5%'         = 'SMC_0603R'                | '(SMC_0603R)'                                   | 'CAP,220PF,5%,50V,C0G,0603'                                                       | 'NFND'    
 'CL100540A'      | '27PF'    | '5%'         = 'SMC_0603R'                | '(SMC_0603R)'                                   | 'CAP,27PF,5%,50V,C0G,0603'                                                        | 'NFND'    
 'CL100542A'      | '330PF'   | '10%'        = 'SMC_0603R'                | '(SMC_0603R)'                                   | 'CAP,330PF,10%,50V,COG,0603'                                                      | 'NFND'    
 'CL100544A'      | '390PF'   | '5%'         = 'SMC_0603R'                | '(SMC_0603R)'                                   | 'CAP,390PF,5%,50V,COG,0603'                                                       | 'NFND'    
 'CL100545A'      | '68PF'    | '5%'         = 'SMC_0603R'                | '(SMC_0603R)'                                   | 'CAP,68PF,5%,50V,C0G,0603'                                                        | 'NFND'    
 'CL100546A'      | '680PF'   | '5%'         = 'SMC_0603R'                | '(SMC_0603R)'                                   | 'CAP,680PF,5%,50V,C0G,0603'                                                       | 'NFND'    
 'CL100547A'      | '820PF'   | '10%'        = 'SMC_0603R'                | '(SMC_0603R)'                                   | 'CAP,820PF,10%,50V,COG,0603'                                                      | 'NFND'    
 'CL100549A'      | '0.01UF'  | '10%'        = 'SMC_0603R'                | '(SMC_0603R)'                                   | 'CAP,0.01UF,10%,50V,X7R,0603'                                                     | 'NFND'    
 'CL100550A'      | '0.1UF'   | '10%'        = 'SMC_0603R'                | '(SMC_0603R)'                                   | 'CAP,0.1UF,10%,16V,X7R,0603'                                                      | 'NFND'    
 'CL100551A'      | '0.1UF'   | '10%'        = 'SMC_0603R'                | '(SMC_0603R)'                                   | 'CAP,0.1UF,10%,25V,X7R,0603'                                                      | 'NFND'    
 'CL100552A'      | '1500PF'  | '10%'        = 'SMC_0603R'                | '(SMC_0603R)'                                   | 'CAP,1500PF,10%,50V,X7R,0603'                                                     | 'NFND'    
 'CL100553A'      | '0.015UF' | '10%'        = 'SMC_0603R'                | '(SMC_0603R)'                                   | 'CAP,0.015UF,10%,50V,X7R,0603'                                                    | 'NFND'    
 'CL100554A'      | '0.15UF'  | '10%'        = 'SMC_0603R'                | '(SMC_0603R)'                                   | 'CAP,0.15UF,10%,25V,X7R,0603'                                                     | 'NFND'    
 'CL100555A'      | '2200PF'  | '10%'        = 'SMC_0603R'                | '(SMC_0603R)'                                   | 'CAP,2200PF,10%,50V,X7R,0603'                                                     | 'NFND'    
 'G101-00007-01'  | '2200PF'  | '10%'        = 'SMC_0603R'                | '(SMC_0603R)'                                   | 'CAP,2200PF,10%,50V,X7R,0603'                                                     | 'NFND'    
 'CL100556A'      | '0.022UF' | '10%'        = 'SMC_0603R'                | '(SMC_0603R)'                                   | 'CAP,0.022UF,10%,50V,X7R,0603'                                                    | 'NFND'    
 'CL100557A'      | '0.22UF'  | '10%'        = 'SMC_0603R'                | '(SMC_0603R)'                                   | 'CAP,0.22UF,10%,10V,X7R,0603'                                                     | 'NFND'    
 'CL100558A'      | '0.22UF'  | '10%'        = 'SMC_0603R'                | '(SMC_0603R)'                                   | 'CAP,0.22UF,10%,16V,X7R,0603'                                                     | 'NFND'    
 'CL100559A'      | '3300PF'  | '10%'        = 'SMC_0603R'                | '(SMC_0603R)'                                   | 'CAP,3300PF,10%,50V,X7R,0603'                                                     | 'NFND'    
 'CL100560A'      | '68000PF' | '10%'        = 'SMC_0603R'                | '(SMC_0603R)'                                   | 'CAP,68000PF,10%,50V,X7R,0603'                                                    | 'NFND'    
 'CL100562A'      | '1UF'     | '+80/-20%'    = 'SMC_0603R'                | '(SMC_0603R)'                                   | 'CAP,1UF,+80/-20%,10V,Y5V,0603'                                                   | 'NFND'    
 'CL100563A'      | '0.47UF'  | '+80/-20%'    = 'SMC_0603R'                | '(SMC_0603R)'                                   | 'CAP,0.47UF,+80/-20%,16V,Y5V,0603'                                                | 'NFND'    
 'CL100564A'      | '1.0UF'   | '10%'        = 'SMC_0805R'                | '(SMC_0805R)'                                   | 'CAP,1.0UF,10%,16V,X7R,0805'                                                      | 'NFND'    
 'CL100565A'      | '0.150UF' | '10%'        = 'SMC_0805R'                | '(SMC_0805R)'                                   | 'CAP,0.150UF,10%,50V,X7R,0805'                                                    | 'NFND'    
 'CL100566A'      | '2.2UF'   | '10%'        = 'SMC_0805R'                | '(SMC_0805R)'                                   | 'CAP,2.2UF,10%,10V,X7R,0805'                                                      | 'NFND'    
 'CL100567A'      | '22UF'    | '20%'        = 'SMC_0805R'                | '(SMC_0805R)'                                   | 'CAP,22UF,20%,6.3V,X5R,CER,0805'                                                  | 'NFND'    
 'G101-00021-01'  | '22UF'    | '20%'        = 'SMC_0805R'                | '(SMC_0805R)'                                   | 'CAP,22UF,20%,6.3V,X5R,CER,0805'                                                  | 'NFND'    
 'CL100568A'      | '4.7UF'   | '10%'        = 'SMC_0805R'                | '(SMC_0805R)'                                   | 'CAP,4.7UF,10%,6.3V,X5R,0805'                                                     | 'NFND'    
 'CL100569A'      | '10UF'    | '10%'        = 'SMC_1206R'                | '(SMC_1206R)'                                   | 'CAP,10UF,10%,10V,X7R,1206'                                                       | 'NFND'    
 'CL100570A'      | '10UF'    | '10%'        = 'SMC_1206R'                | '(SMC_1206R)'                                   | 'CAP,10UF,10%,25V,X5R,1206'                                                       | 'NFND'    
 'G101-00009-01'  | '10UF'    | '10%'        = 'SMC_1206R_H071'           | '(SMC_1206R_H071)'                              | 'CAP,10UF,10%,25V,X5R,1206'                                                       | 'NFND'    
 'CL100571A'      | '4.7UF'   | '10%'        = 'SMC_1206R'                | '(SMC_1206R)'                                   | 'CAP,4.7UF,10%,10V,X5R,1206'                                                      | 'NFND'    
 'CL100572A'      | '100UF'   | '20%'        = 'SMC_1210R'                | '(SMC_1210R)'                                   | 'CAP,100UF,20%,6.3V,X5R,CER,1210'                                                 | 'NFND'    
 'CL100573A'      | '22UF'    | '10%'        = 'SMC_1210R'                | '(SMC_1210R)'                                   | 'CAP,22UF,10%,16V,X5R,CER,1210'                                                   | 'NFND'    
 'CL100574A'      | '22UF'    | '10%'        = 'SMC_1210R'                | '(SMC_1210R)'                                   | 'CAP,22UF,10%,25V,X5R,1210'                                                       | 'NFND'    
 'CL100575A'      | '47UF'    | '10%'        = 'SMC_1210R'                | '(SMC_1210R)'                                   | 'CAP,47UF,10%,16V,X5R,1210'                                                       | 'NFND'    
 'CL100576A'      | '100PF'   | '5%'         = 'SMC_0603R'                | '(SMC_0603R)'                                   | 'CAPACITOR,100PF,FIXED,CERAMIC,COG/NPO,5%,50V,-55/125C,SMD,0603'                  | 'NFND'    
 'CL100578A'      | '33PF'    | '5%'         = 'SMC_0603R'                | '(SMC_0603R)'                                   | 'CAPACITOR,33PF,FIXED,CERAMIC,COG/NPO,5%,50V,-55/125C,SMD,0603'                   | 'NFND'    
 'CL100579A'      | '39PF'    | '5%'         = 'SMC_0603R'                | '(SMC_0603R)'                                   | 'CAPACITOR,39PF,FIXED,CERAMIC,C0G,5%,50V,-55/125C,SMD,0603'                       | 'NFND'    
 'CL100580A'      | '10000PF' | '10%'        = 'SMC_0603R'                | '(SMC_0603R)'                                   | 'CAPACITOR,10000PF,FIXED,CERAMIC,X7R,10%,50V,-55/125C,SMD,0603'                   | 'NFND'    
 'CL100581A'      | '15000PF' | '10%%'       = 'SMC_0603R'                | '(SMC_0603R)'                                   | 'CAPACITOR,15000PF,FIXED,CERAMIC,X7R,10%%,50V,-55/125C,SMD,0603'                  | 'NFND'    
 'CL100582A'      | '22000PF' | '10%%'       = 'SMC_0603R'                | '(SMC_0603R)'                                   | 'CAPACITOR,22000PF,FIXED,CERAMIC,X7R,10%%,50V,-55/125C,SMD,0603'                  | 'NFND'    
 'CL100583A'      | '0.33UF'  | '10%'        = 'SMC_0805R'                | '(SMC_0805R)'                                   | 'CAPACITOR,0.33UF,FIXED,CERAMIC,X7R,10%,16V,SMD,0805'                             | 'NFND'    
 'CL100584A'      | '0.1UF'   | '10%'        = 'SMC_1206R'                | '(SMC_1206R)'                                   | 'CAPACITOR,0.1UF,FIXED,CERAMIC,X7R,10%,100V,-55/125C,SMD,1206'                    | 'NFND'    
 'G101-00028-01'  | '0.1UF'   | '10%'        = 'SMC_1206R'                | '(SMC_1206R)'                                   | 'CAPACITOR,0.1UF,FIXED,CERAMIC,X7R,10%,100V,-55/125C,SMD,1206'                    | 'REJECTED'
 'CL100585A'      | '100UF'   | '+80/-20%'    = 'XXXX'                     | '(XXXX)'                                        | 'CAP,100UF,+80/-20%,16V,Y5V,2220'                                                 | 'NFND'    
 'CL100586A'      | '47UF'    | '20%'        = 'SMC_C_224X196'            | '(SMC_C_224X196)'                               | 'CAP,47UF,20%,16V,X5R,CER,2220'                                                   | 'NFND'    
 'CL100587A'      | '180PF'   | '5%'         = 'SMC_0402R'                | '(SMC_0402R_C)'                                 | 'CAP,180PF,5%,50V,C0G,0402'                                                       | 'NFND'    
 'CL100588A'      | '470PF'   | '5%'         = 'SMC_0402R'                | '(SMC_0402R_C)'                                 | 'CAP,470PF,5%,50V,C0G,0402'                                                       | 'NFND'    
 'CL100589A'      | '4700PF'  | '10%'        = 'SMC_0402R'                | '(SMC_0402R_C)'                                 | 'CAP,4700PF,10%,25V,X7R,CER,0402'                                                 | 'NFND'    
 'CL100590A'      | '1.0UF'   | '10%'        = 'SMC_0402R'                | '(SMC_0402R_C)'                                 | 'CAP,1.0UF,10%,6.3V,X5R,0402'                                                     | 'NFND'    
 'CL100591A'      | '120PF'   | '10%'        = 'SMC_0603R'                | '(SMC_0603R)'                                   | 'CAP,120PF,10%,50V,COG,CER,0603'                                                  | 'NFND'    
 'G101-00004-01'  | '120PF'   | '10%'        = 'SMC_0603R'                | '(SMC_0603R)'                                   | 'CAP,120PF,10%,50V,COG,CER,0603'                                                  | 'OBSOLETE'
 'CL100599A'      | '680PF'   | '5%'         = 'SMC_0603R'                | '(SMC_0603R)'                                   | 'CAP,680PF,5%,50V,C0G,0603'                                                       | 'NFND'    
 'CL100600A'      | '0.15UF'  | '10%'        = 'SMC_0603R'                | '(SMC_0603R)'                                   | 'CAP,0.15UF,10%,25V,X7R,0603'                                                     | 'NFND'    
 'CL100602A'      | '0.033UF' | '10%'        = 'SMC_0603R'                | '(SMC_0603R)'                                   | 'CAP,0.033UF,10%,50V,X7R,0603'                                                    | 'NFND'    
 'CL100603A'      | '68000PF' | '10%'        = 'SMC_0603R'                | '(SMC_0603R)'                                   | 'CAP,68000PF,10%,50V,X7R,0603'                                                    | 'NFND'    
 'CL100604A'      | '2.2UF'   | '10%'        = 'SMC_0603R'                | '(SMC_0603R)'                                   | 'CAP,2.2UF,10%,6.3V,X5R,CER,0603'                                                 | 'NFND'    
 'G101-00022-01'  | '2.2UF'   | '10%'        = 'SMC_0603R'                | '(SMC_0603R)'                                   | 'CAP,2.2UF,10%,6.3V,X5R,CER,0603'                                                 | 'NFND'    
 'CL100605A'      | '1.0UF'   | '10%'        = 'SMC_0805R'                | '(SMC_0805R)'                                   | 'CAP,1.0UF,10%,16V,X7R,0805'                                                      | 'NFND'    
 'CL100606A'      | '1.0UF'   | '10%'        = 'SMC_0805R'                | '(SMC_0805R)'                                   | 'CAP,1.0UF,10%,16V,X5R,CER,0805'                                                  | 'NFND'    
 'CL100607A'      | '10UF'    | '10%'        = 'SMC_0805R'                | '(SMC_0805R)'                                   | 'CAP,10UF,10%,6.3V,X5R,CER,0805'                                                  | 'NFND'    
 'G101-00008-01'  | '10UF'    | '10%'        = 'SMC_0805R'                | '(SMC_0805R)'                                   | 'CAP,10UF,10%,6.3V,X5R,CER,0805'                                                  | 'NFND'    
 'CL100610A'      | '4.7UF'   | '20%'        = 'SMC_0805R'                | '(SMC_0805R)'                                   | 'CAP,4.7UF,20%,6.3V,X5R,0805'                                                     | 'NFND'    
 'CL100611A'      | '4.7UF'   | '20%'        = 'SMC_1206R'                | '(SMC_1206R)'                                   | 'CAP,4.7UF,20%,16V,X5R,CER,1206'                                                  | 'NFND'    
 'G101-00005-01'  | '4.7UF'   | '20%'        = 'SMC_1206R'                | '(SMC_1206R)'                                   | 'CAP,4.7UF,20%,16V,X5R,CER,1206'                                                  | 'NFND'    
 'CL100614A'      | '47UF'    | '20%'        = 'SMC_1210R'                | '(SMC_1210R)'                                   | 'CAP,47UF,20%,6.3V,X5R,CER,1210'                                                  | 'NFND'    
 'CL100615A'      | '22UF'    | '+80/-20%'    = 'SMC_1210R'                | '(SMC_1210R)'                                   | 'CAP,22UF,+80/-20%,10V,Y5V,1210'                                                  | 'NFND'    
 'CL100616A'      | '47UF'    | '+80/-20%'    = 'SMC_1210R'                | '(SMC_1210R)'                                   | 'CAP,47UF,+80/-20%,10V,Y5V,CER,1210'                                              | 'NFND'    
 'CL100617A'      | '0.22UF'  | '10%'        = 'SMC_0805R'                | '(SMC_0805R)'                                   | 'CAP,0.22UF,X7R,10%,50V,0805,ROHS'                                                | 'NFND'    
 'CL100618A'      | '1500PF'  | '5%'         = 'SMC_0603R'                | '(SMC_0603R)'                                   | 'CAP,1500PF,NPO,5%,50V,0603,ROHS'                                                 | 'NFND'    
 'CL100619A'      | '15PF'    | '5%'         = 'SMC_0603R'                | '(SMC_0603R)'                                   | 'CAP,15PF,NPO,5%,50V,0603,ROHS'                                                   | 'NFND'    
 'CL100620A'      | '220PF'   | '5%'         = 'SMC_0603R'                | '(SMC_0603R)'                                   | 'CAP,220PF,NPO,5%,50V,0603,ROHS'                                                  | 'NFND'    
 'CL100621A'      | '330PF'   | '5%'         = 'SMC_0603R'                | '(SMC_0603R)'                                   | 'CAP,330PF,NPO,5%,50V,0603,ROHS'                                                  | 'NFND'    
 'CL100623A'      | '47PF'    | '5%'         = 'SMC_0603R'                | '(SMC_0603R)'                                   | 'CAP,47PF,NPO,5%,50V,0603,ROHS'                                                   | 'NFND'    
 'CL100624A'      | '560PF'   | '5%'         = 'SMC_0603R'                | '(SMC_0603R)'                                   | 'CAP,560PF,NPO,5%,50V,0603,ROHS'                                                  | 'NFND'    
 'CL100626A'      | '10UF'    | '20%'        = 'SMC_0805R'                | '(SMC_0805R)'                                   | 'CAP,CER,10U,20%,6.3V,0805'                                                       | 'NFND'    
 'CL100627A'      | '22UF'    | '20%'        = 'SMC_1210R'                | '(SMC_1210R)'                                   | 'CAP,CER,22U,20%,16V,1210'                                                        | 'NFND'    
 'CL100628A'      | '4.7UF'   | '20%'        = 'SMC_0603R'                | '(SMC_0603R)'                                   | 'CAP,CER,4.7U,20%,6.3V,0603'                                                      | 'NFND'    
 'CL100629A'      | '68PF'    | '5%'         = 'SMC_0603R'                | '(SMC_0603R)'                                   | 'CAP,CER,68P,5%,50V,0603'                                                         | 'NFND'    
 'CL100630A'      | '18PF'    | '5%'         = 'SMC_0603R'                | '(SMC_0603R)'                                   | 'CAP,18PF,NPO,5%,50V,0603,ROHS'                                                   | 'NFND'    
 'CL100631A'      | '22UF'    | '20%'        = 'SMC_1812R'                | '(SMC_1812R)'                                   | 'CAP,22UF,X5R,20%,25V,1812,ROHS'                                                  | 'NFND'    
 'CL100632A'      | '5PF'     | '5%'         = 'SMC_0402R'                | '(SMC_0402R_C)'                                 | 'CAP,5PF,COG,5%,50V,0402,ROHS'                                                    | 'NFND'    
 'CL100633A'      | '1000PF'  | '10%'        = 'SMC_0402R'                | '(SMC_0402R_C)'                                 | 'CAP,CER,1000PF,10%,50VX7R,0402,ROHS'                                             | 'NFND'    
 'CL100634A'      | '1UF'     | '10%'        = 'SMC_0603R'                | '(SMC_0603R)'                                   | 'CAP,CER,1UF,10%,25V,0603,X5R,ROHS'                                               | 'NFND'    
 'G101-00023-01'  | '1UF'     | '10%'        = 'SMC_0603R'                | '(SMC_0603R)'                                   | 'CAP,CER,1UF,10%,25V,0603,X5R,ROHS'                                               | 'NFND'    
 'CL100635A'      | '100UF'   | '20%'        = 'SMC_1210R'                | '(SMC_1210R)'                                   | 'CAP,100UF,X5R,20%,6.3V,1210,ROHS'                                                | 'NFND'    
 'CL100636A'      | '2.2UF'   | '20%'        = 'SMC_0603R'                | '(SMC_0603R)'                                   | 'CAP,2.2UF,X7R,20%,6.3V,0603,ROHS'                                                | 'NFND'    
 'CL100637A'      | '22PF'    | '5%'         = 'SMC_0603R'                | '(SMC_0603R)'                                   | 'CAP,22PF,NPO,5%,50V,0603,ROHS'                                                   | 'NFND'    
 'CL100638A'      | '22UF'    | '20%'        = 'SMC_0805R'                | '(SMC_0805R)'                                   | 'CAP,22UF,X5R,20%,6.3V,0805,ROHS'                                                 | 'NFND'    
 'CL100639A'      | '27PF'    | '5%'         = 'SMC_0603R'                | '(SMC_0603R)'                                   | 'CAP,27PF,NPO,5%,50V,0603,ROHS'                                                   | 'NFND'    
 'CL100640A'      | '2UF'     | '10%'        = 'SMC_0603R'                | '(SMC_0603R)'                                   | 'CAP,2UF,X7R,10%,16V,0603,ROHS'                                                   | 'NFND'    
 'CL100641A'      | '12PF'    | '5%'         = 'SMC_0603R'                | '(SMC_0603R)'                                   | 'CAP,12PF,NPO,5%,50V,0603,ROHS'                                                   | 'NFND'    
 'CL1001363A'     | '1NF'     | '20%'        = 'SMC_1808'                 | '(SMC_1808)'                                    | 'CAP, 1808, X7R, 20%, 2KV, 1000PF, ROHS'                                          | 'NFND'    
 'CL1001364A'     | '0.1UF'   | '10%'        = 'SMC_0402R'                | '(SMC_0402R_C)'                                 | 'CAP,0.1UF,10%,16V,X5R,0402'                                                      | 'NFND'    
 'G101-00015-01'  | '0.1UF'   | '10%'        = 'SMC_0402R'                | '(SMC_0402R_C)'                                 | 'CAP,0.1UF,10%,16V,X5R,0402'                                                      | 'NFND'    
 'CL1001425A'     | '4.7PF'   | '+/-0.25PF'    = 'SMC_0402R'                | '(SMC_0402R_C)'                                 | 'CAP, 4.7PF, +/-0.25PF, 50V, C0G, 0402'                                           | 'NFND'    
 'CL1001347A'     | '100NF'   | '20%'        = 'SMC_0402R'                | '(SMC_0402R_C)'                                 | 'CAP, 100NF, 20%, 16V DC, -55~+85C, 0402'                                         | 'NFND'    
 'CL1003000A'     | '1PF'     | '+/-0.25PF'    = 'SMC_0201'                 | '(SMC_0201)'                                    | 'CAP, 1PF, +/-0.25PF, 25V, C0G, 0201'                                             | 'NFND'    
 'CL1003001A'     | '2PF'     | '+/-0.25PF'    = 'SMC_0201'                 | '(SMC_0201)'                                    | 'CAP, 2PF, +/-0.25PF, 25V, C0G, 0201'                                             | 'NFND'    
 'CL1003002A'     | '3PF'     | '+/-0.25PF'    = 'SMC_0201'                 | '(SMC_0201)'                                    | 'CAP, 3PF, +/-0.25PF, 25V, C0G, 0201'                                             | 'NFND'    
 'CL1003003A'     | '4PF'     | '+/-0.25PF'    = 'SMC_0201'                 | '(SMC_0201)'                                    | 'CAP, 4PF, +/-0.25PF, 25V, C0G, 0201'                                             | 'NFND'    
 'CL1003004A'     | '5PF'     | '+/-0.25PF'    = 'SMC_0201'                 | '(SMC_0201)'                                    | 'CAP, 5PF, +/-0.25PF, 25V, C0G, 0201'                                             | 'NFND'    
 'CL1003005A'     | '6PF'     | '+/-0.5PF'    = 'SMC_0201'                 | '(SMC_0201)'                                    | 'CAP, 6PF, +/-0.5PF, 25V, C0G, 0201'                                              | 'NFND'    
 'CL1003006A'     | '7PF'     | '+/-0.5PF'    = 'SMC_0201'                 | '(SMC_0201)'                                    | 'CAP, 7PF, +/-0.5PF, 25V, C0G, 0201'                                              | 'NFND'    
 'CL1003007A'     | '8PF'     | '+/-0.5PF'    = 'SMC_0201'                 | '(SMC_0201)'                                    | 'CAP, 8PF, +/-0.5PF, 25V, C0G, 0201'                                              | 'NFND'    
 'CL1003008A'     | '9PF'     | '+/-0.5PF'    = 'SMC_0201'                 | '(SMC_0201)'                                    | 'CAP, 9PF, +/-0.5PF, 25V, C0G, 0201'                                              | 'NFND'    
 'CL1003009A'     | '0.5PF'   | '+/-0.25PF'    = 'SMC_0201'                 | '(SMC_0201)'                                    | 'CAP, 0.5PF, +/-0.25PF, 25V, C0G, 0201'                                           | 'NFND'    
 'CL1003010A'     | '10PF'    | '+/-0.5PF'    = 'SMC_0201'                 | '(SMC_0201)'                                    | 'CAP, 10PF, +/-0.5PF, 25V, C0G, 0201'                                             | 'NFND'    
 'CL1003011A'     | '100PF'   | '+/-5%'      = 'SMC_0201'                 | '(SMC_0201)'                                    | 'CAP, 100PF, +/-5%, 25V, C0G, 0201'                                               | 'NFND'    
 'CL1003012A'     | '12PF'    | '+/-5%'      = 'SMC_0201'                 | '(SMC_0201)'                                    | 'CAP, 12PF, +/-5%, 25V, C0G, 0201'                                                | 'NFND'    
 'CL1003013A'     | '15PF'    | '+/-5%'      = 'SMC_0201'                 | '(SMC_0201)'                                    | 'CAP, 15PF, +/-5%, 25V, C0G, 0201'                                                | 'NFND'    
 'CL1003014A'     | '18PF'    | '+/-5%'      = 'SMC_0201'                 | '(SMC_0201)'                                    | 'CAP, 18PF, +/-5%, 25V, C0G, 0201'                                                | 'NFND'    
 'CL1003015A'     | '1.5PF'   | '+/-0.25PF'    = 'SMC_0201'                 | '(SMC_0201)'                                    | 'CAP, 1.5PF, +/-0.25PF, 25V, C0G, 0201'                                           | 'NFND'    
 'CL1003016A'     | '22PF'    | '+/-5%'      = 'SMC_0201'                 | '(SMC_0201)'                                    | 'CAP, 22PF, +/-5%, 25V, C0G, 0201'                                                | 'NFND'    
 'CL1003017A'     | '27PF'    | '+/-5%'      = 'SMC_0201'                 | '(SMC_0201)'                                    | 'CAP, 27PF, +/-5%, 25V, C0G, 0201'                                                | 'NFND'    
 'CL1003018A'     | '2.2PF'   | '+/-0.25PF'    = 'SMC_0201'                 | '(SMC_0201)'                                    | 'CAP, 2.2PF, +/-0.25PF, 25V, C0G, 0201'                                           | 'NFND'    
 'CL1003019A'     | '33PF'    | '+/-5%'      = 'SMC_0201'                 | '(SMC_0201)'                                    | 'CAP, 33PF, +/-5%, 25V, C0G, 0201'                                                | 'NFND'    
 'CL1003020A'     | '39PF'    | '+/-5%'      = 'SMC_0201'                 | '(SMC_0201)'                                    | 'CAP, 39PF, +/-5%, 25V, C0G, 0201'                                                | 'NFND'    
 'CL1003021A'     | '3.3PF'   | '+/-0.25PF'    = 'SMC_0201'                 | '(SMC_0201)'                                    | 'CAP, 3.3PF, +/-0.25PF, 25V, C0G, 0201'                                           | 'NFND'    
 'CL1003022A'     | '47PF'    | '+/-5%'      = 'SMC_0201'                 | '(SMC_0201)'                                    | 'CAP, 47PF, +/-5%, 25V, C0G, 0201'                                                | 'NFND'    
 'CL1003023A'     | '4.7PF'   | '+/-0.25PF'    = 'SMC_0201'                 | '(SMC_0201)'                                    | 'CAP, 4.7PF, +/-0.25PF, 25V, C0G, 0201'                                           | 'NFND'    
 'CL1003024A'     | '56PF'    | '+/-5%'      = 'SMC_0201'                 | '(SMC_0201)'                                    | 'CAP, 56PF, +/-5%, 25V, C0G, 0201'                                                | 'NFND'    
 'CL1003025A'     | '68PF'    | '+/-5%'      = 'SMC_0201'                 | '(SMC_0201)'                                    | 'CAP, 68PF, +/-5%, 25V, C0G, 0201'                                                | 'NFND'    
 'CL1003026A'     | '6.8PF'   | '+/-0.5PF'    = 'SMC_0201'                 | '(SMC_0201)'                                    | 'CAP, 6.8PF, +/-0.5PF, 25V, C0G, 0201'                                            | 'NFND'    
 'CL1003027A'     | '82PF'    | '+/-5%'      = 'SMC_0201'                 | '(SMC_0201)'                                    | 'CAP, 82PF, +/-5%, 25V, C0G, 0201'                                                | 'NFND'    
 'CL1003028A'     | '100NF'   | '+/-10%'     = 'SMC_0201'                 | '(SMC_0201)'                                    | 'CAP, 100NF, +/-10%, 6.3V, X5R, 0201'                                             | 'NFND'    
 'CL1003029A'     | '100NF'   | '+/-20%'     = 'SMC_0201'                 | '(SMC_0201)'                                    | 'CAP, 100NF, +/-20%, 6.3V, X5R, 0201'                                             | 'NFND'    
 'CL1003030A'     | '22NF'    | '+/-10%'     = 'SMC_0201'                 | '(SMC_0201)'                                    | 'CAP, 22NF, +/-10%, 6.3V, X5R, 0201'                                              | 'NFND'    
 'CL1003031A'     | '47NF'    | '+/-10%'     = 'SMC_0201'                 | '(SMC_0201)'                                    | 'CAP, 47NF, +/-10%, 6.3V, X5R, 0201'                                              | 'NFND'    
 'CL1003032A'     | '10NF'    | '+/-10%'     = 'SMC_0201'                 | '(SMC_0201)'                                    | 'CAP, 10NF, +/-10%, 10V, X5R, 0201'                                               | 'NFND'    
 'CL1003033A'     | '4700PF'  | '+/-10%'     = 'SMC_0201'                 | '(SMC_0201)'                                    | 'CAP, 4700PF, +/-10%, 16V, X5R, 0201'                                             | 'NFND'    
 'CL1003034A'     | '100PF'   | '+/-10%'     = 'SMC_0201'                 | '(SMC_0201)'                                    | 'CAP, 100PF, +/-10%, 25V, X5R, 0201'                                              | 'NFND'    
 'CL1003035A'     | '1000PF'  | '+/-10%'     = 'SMC_0201'                 | '(SMC_0201)'                                    | 'CAP, 1000PF, +/-10%, 25V, X5R, 0201'                                             | 'NFND'    
 'CL1003036A'     | '220PF'   | '+/-10%'     = 'SMC_0201'                 | '(SMC_0201)'                                    | 'CAP, 220PF, +/-10%, 25V, X5R, 0201'                                              | 'NFND'    
 'CL1003037A'     | '2200PF'  | '+/-10%'     = 'SMC_0201'                 | '(SMC_0201)'                                    | 'CAP, 2200PF, +/-10%, 25V, X5R, 0201'                                             | 'NFND'    
 'CL1003038A'     | '470PF'   | '+/-10%'     = 'SMC_0201'                 | '(SMC_0201)'                                    | 'CAP, 470PF, +/-10%, 25V, X5R, 0201'                                              | 'NFND'    
 'CL1003039A'     | '10NF'    | '-20/+80%'    = 'SMC_0201'                 | '(SMC_0201)'                                    | 'CAP, 10NF, -20/+80%, 16V, Y5V, 0201'                                             | 'NFND'    
 'CL1003040A'     | '1PF'     | '+/-0.25PF'    = 'SMC_0402R'                | '(SMC_0402R_C)'                                 | 'CAP, 1PF, +/-0.25PF, 50V, C0G, 0402'                                             | 'NFND'    
 'CL1003041A'     | '3PF'     | '+/-0.25PF'    = 'SMC_0402R'                | '(SMC_0402R_C)'                                 | 'CAP, 3PF, +/-0.25PF, 50V, C0G, 0402'                                             | 'NFND'    
 'CL1003042A'     | '4PF'     | '+/-0.25PF'    = 'SMC_0402R'                | '(SMC_0402R_C)'                                 | 'CAP, 4PF, +/-0.25PF, 50V, C0G, 0402'                                             | 'NFND'    
 'CL1003043A'     | '6PF'     | '+/-0.5PF'    = 'SMC_0402R'                | '(SMC_0402R_C)'                                 | 'CAP, 6PF, +/-0.5PF, 50V, C0G, 0402'                                              | 'NFND'    
 'CL1003044A'     | '7PF'     | '+/-0.5PF'    = 'SMC_0402R'                | '(SMC_0402R_C)'                                 | 'CAP, 7PF, +/-0.5PF, 50V, C0G, 0402'                                              | 'NFND'    
 'G101-10013-01'  | '7PF'     | '+/-0.5PF'    = 'SMC_0402R'                | '(SMC_0402R_C)'                                 | 'CAP, 7PF, +/-0.5PF, 50V, C0G, 0402'                                              | 'NFND'    
 'CL1003045A'     | '8PF'     | '+/-0.5PF'    = 'SMC_0402R'                | '(SMC_0402R_C)'                                 | 'CAP, 8PF, +/-0.5PF, 50V, C0G, 0402'                                              | 'NFND'    
 'CL1003046A'     | '9PF'     | '+/-0.5PF'    = 'SMC_0402R'                | '(SMC_0402R_C)'                                 | 'CAP, 9PF, +/-0.5PF, 50V, C0G, 0402'                                              | 'NFND'    
 'CL1003047A'     | '0.5PF'   | '+/-0.25PF'    = 'SMC_0402R'                | '(SMC_0402R_C)'                                 | 'CAP, 0.5PF, +/-0.25PF, 50V, C0G, 0402'                                           | 'NFND'    
 'CL1003048A'     | '10PF'    | '+/-0.5PF'    = 'SMC_0402R'                | '(SMC_0402R_C)'                                 | 'CAP, 10PF, +/-0.5PF, 50V, C0G, 0402'                                             | 'NFND'    
 'G105-0A100-FD'  | '10PF'    | '+/-0.5PF'    = 'SMC_0402R'                | '(SMC_0402R_C)'                                 | 'CAP, 10PF, +/-0.5PF, 50V, C0G, 0402'                                             | 'NFND'    
 'CL1003049A'     | '12PF'    | '+/-5%'      = 'SMC_0402R'                | '(SMC_0402R_C)'                                 | 'CAP, 12PF, +/-5%, 50V, C0G, 0402'                                                | 'NFND'    
 'CL1003050A'     | '120PF'   | '+/-5%'      = 'SMC_0402R'                | '(SMC_0402R_C)'                                 | 'CAP, 120PF, +/-5%, 50V, C0G, 0402'                                               | 'NFND'    
 'G105-0A121-FJ'  | '120PF'   | '+/-5%'      = 'SMC_0402R'                | '(SMC_0402R_C)'                                 | 'CAP, 120PF, +/-5%, 50V, C0G, 0402'                                               | 'NFND'    
 'CL1003051A'     | '15PF'    | '+/-5%'      = 'SMC_0402R'                | '(SMC_0402R_C)'                                 | 'CAP, 15PF, +/-5%, 50V, C0G, 0402'                                                | 'NFND'    
 'G101-00016-01'  | '15PF'    | '+/-5%'      = 'SMC_0402R'                | '(SMC_0402R_C)'                                 | 'CAP, 15PF, +/-5%, 50V, C0G, 0402'                                                | 'NFND'    
 'CL1003052A'     | '150PF'   | '+/-5%'      = 'SMC_0402R'                | '(SMC_0402R_C)'                                 | 'CAP, 150PF, +/-5%, 50V, C0G, 0402'                                               | 'NFND'    
 'CL1003053A'     | '1.5PF'   | '+/-0.25PF'    = 'SMC_0402R'                | '(SMC_0402R_C)'                                 | 'CAP, 1.5PF, +/-0.25PF, 50V, C0G, 0402'                                           | 'NFND'    
 'CL1003054A'     | '20PF'    | '+/-5%'      = 'SMC_0402R'                | '(SMC_0402R_C)'                                 | 'CAP, 20PF, +/-5%, 50V, C0G, 0402'                                                | 'NFND'    
 'CL1003055A'     | '200PF'   | '+/-5%'      = 'SMC_0402R'                | '(SMC_0402R_C)'                                 | 'CAP, 200PF, +/-5%, 50V, C0G, 0402'                                               | 'NFND'    
 'CL1003056A'     | '220PF'   | '+/-5%'      = 'SMC_0402R'                | '(SMC_0402R_C)'                                 | 'CAP, 220PF, +/-5%, 50V, C0G, 0402'                                               | 'NFND'    
 'CL1003057A'     | '27PF'    | '+/-5%'      = 'SMC_0402R'                | '(SMC_0402R_C)'                                 | 'CAP, 27PF, +/-5%, 50V, C0G, 0402'                                                | 'NFND'    
 'G101-00014-01'  | '27PF'    | '+/-5%'      = 'SMC_0402R'                | '(SMC_0402R_C)'                                 | 'CAP, 27PF, +/-5%, 50V, C0G, 0402'                                                | 'NFND'    
 'CL1003058A'     | '270PF'   | '+/-5%'      = 'SMC_0402R'                | '(SMC_0402R_C)'                                 | 'CAP, 270PF, +/-5%, 50V, C0G, 0402'                                               | 'NFND'    
 'G101-00026-01'  | '270PF'   | '+/-5%'      = 'SMC_0402R'                | '(SMC_0402R_C)'                                 | 'CAP, 270PF, +/-5%, 50V, C0G, 0402'                                               | 'OBSOLETE'
 'CL1003059A'     | '2.2PF'   | '+/-0.25PF'    = 'SMC_0402R'                | '(SMC_0402R_C)'                                 | 'CAP, 2.2PF, +/-0.25PF, 50V, C0G, 0402'                                           | 'NFND'    
 'CL1003060A'     | '30PF'    | '+/-5%'      = 'SMC_0402R'                | '(SMC_0402R_C)'                                 | 'CAP, 30PF, +/-5%, 50V, C0G, 0402'                                                | 'NFND'    
 'CL1003061A'     | '33PF'    | '+/-5%'      = 'SMC_0402R'                | '(SMC_0402R_C)'                                 | 'CAP, 33PF, +/-5%, 50V, C0G, 0402'                                                | 'NFND'    
 'CL1003062A'     | '330PF'   | '+/-5%'      = 'SMC_0402R'                | '(SMC_0402R_C)'                                 | 'CAP, 330PF, +/-5%, 50V, C0G, 0402'                                               | 'NFND'    
 'CL1003063A'     | '39PF'    | '+/-5%'      = 'SMC_0402R'                | '(SMC_0402R_C)'                                 | 'CAP, 39PF, +/-5%, 50V, C0G, 0402'                                                | 'NFND'    
 'CL1003064A'     | '390PF'   | '+/-5%'      = 'SMC_0402R'                | '(SMC_0402R_C)'                                 | 'CAP, 390PF, +/-5%, 50V, C0G, 0402'                                               | 'NFND'    
 'CL1003065A'     | '3.3PF'   | '+/-0.25PF'    = 'SMC_0402R'                | '(SMC_0402R_C)'                                 | 'CAP, 3.3PF, +/-0.25PF, 50V, C0G, 0402'                                           | 'NFND'    
 'CL1003066A'     | '56PF'    | '+/-5%'      = 'SMC_0402R'                | '(SMC_0402R_C)'                                 | 'CAP, 56PF, +/-5%, 50V, C0G, 0402'                                                | 'NFND'    
 'CL1003067A'     | '68PF'    | '+/-5%'      = 'SMC_0402R'                | '(SMC_0402R_C)'                                 | 'CAP, 68PF, +/-5%, 50V, C0G, 0402'                                                | 'NFND'    
 'CL1003068A'     | '100NF'   | '+/-10%'     = 'SMC_0402R'                | '(SMC_0402R_C)'                                 | 'CAP, 100NF, +/-10%, 6.3V, X5R, 0402'                                             | 'NFND'    
 'CL1003069A'     | '220NF'   | '+/-10%'     = 'SMC_0402R'                | '(SMC_0402R_C)'                                 | 'CAP, 220NF, +/-10%, 6.3V, X5R, 0402'                                             | 'NFND'    
 'CL1003070A'     | '330NF'   | '+/-10%'     = 'SMC_0402R'                | '(SMC_0402R_C)'                                 | 'CAP, 330NF, +/-10%, 6.3V, X5R, 0402'                                             | 'NFND'    
 'CL1003071A'     | '470NF'   | '+/-10%'     = 'SMC_0402R'                | '(SMC_0402R_C)'                                 | 'CAP, 470NF, +/-10%, 6.3V, X5R, 0402'                                             | 'NFND'    
 'CL1003072A'     | '680NF'   | '+/-10%'     = 'SMC_0402R'                | '(SMC_0402R_C)'                                 | 'CAP, 680NF, +/-10%, 6.3V, X5R, 0402'                                             | 'NFND'    
 'CL1003073A'     | '100NF'   | '+/-10%'     = 'SMC_0402R'                | '(SMC_0402R_C)'                                 | 'CAP, 100NF, +/-10%, 10V, X5R, 0402'                                              | 'NFND'    
 'CL1003074A'     | '1UF'     | '+/-20%'     = 'SMC_0402R'                | '(SMC_0402R_C)'                                 | 'CAP, 1UF, +/-20%, 10V, X5R, 0402'                                                | 'NFND'    
 'CL1003075A'     | '220NF'   | '+/-10%'     = 'SMC_0402R'                | '(SMC_0402R_C)'                                 | 'CAP, 220NF, +/-10%, 10V, X5R, 0402'                                              | 'NFND'    
 'CL1003076A'     | '330NF'   | '+/-10%'     = 'SMC_0402R'                | '(SMC_0402R_C)'                                 | 'CAP, 330NF, +/-10%, 10V, X5R, 0402'                                              | 'NFND'    
 'CL1003077A'     | '220NF'   | '+/-10%'     = 'SMC_0402R'                | '(SMC_0402R_C)'                                 | 'CAP, 220NF, +/-10%, 16V, X5R, 0402'                                              | 'NFND'    
 'CL1003078A'     | '47NF'    | '+/-10%'     = 'SMC_0402R'                | '(SMC_0402R_C)'                                 | 'CAP, 47NF, +/-10%, 16V, X5R, 0402'                                               | 'NFND'    
 'CL1003079A'     | '68NF'    | '+/-10%'     = 'SMC_0402R'                | '(SMC_0402R_C)'                                 | 'CAP, 68NF, +/-10%, 16V, X5R, 0402'                                               | 'NFND'    
 'CL1003080A'     | '10NF'    | '+/-10%'     = 'SMC_0402R'                | '(SMC_0402R_C)'                                 | 'CAP, 10NF, +/-10%, 25V, X5R, 0402'                                               | 'NFND'    
 'G101-00017-01'  | '10NF'    | '+/-10%'     = 'SMC_0402R'                | '(SMC_0402R_C)'                                 | 'CAP, 10NF, +/-10%, 25V, X5R, 0402'                                               | 'NFND'    
 'CL1003081A'     | '100NF'   | '+/-10%'     = 'SMC_0402R'                | '(SMC_0402R_C)'                                 | 'CAP, 100NF, +/-10%, 25V, X5R, 0402'                                              | 'NFND'    
 'CL1003082A'     | '22NF'    | '+/-10%'     = 'SMC_0402R'                | '(SMC_0402R_C)'                                 | 'CAP, 22NF, +/-10%, 25V, X5R, 0402'                                               | 'NFND'    
 'CL1003083A'     | '47NF'    | '+/-10%'     = 'SMC_0402R'                | '(SMC_0402R_C)'                                 | 'CAP, 47NF, +/-10%, 25V, X5R, 0402'                                               | 'NFND'    
 'CL1003084A'     | '68NF'    | '+/-10%'     = 'SMC_0402R'                | '(SMC_0402R_C)'                                 | 'CAP, 68NF, +/-10%, 25V, X5R, 0402'                                               | 'NFND'    
 'CL1003085A'     | '100NF'   | '+/-10%'     = 'SMC_0402R'                | '(SMC_0402R_C)'                                 | 'CAP, 100NF, +/-10%, 6.3V, X7R, 0402'                                             | 'NFND'    
 'CL1003086A'     | '100NF'   | '+/-10%'     = 'SMC_0402R'                | '(SMC_0402R_C)'                                 | 'CAP, 100NF, +/-10%, 10V, X7R, 0402'                                              | 'NFND'    
 'CL1003087A'     | '33NF'    | '+/-10%'     = 'SMC_0402R'                | '(SMC_0402R_C)'                                 | 'CAP, 33NF, +/-10%, 10V, X7R, 0402'                                               | 'NFND'    
 'CL1003088A'     | '47NF'    | '+/-10%'     = 'SMC_0402R'                | '(SMC_0402R_C)'                                 | 'CAP, 47NF, +/-10%, 10V, X7R, 0402'                                               | 'NFND'    
 'CL1003089A'     | '15NF'    | '+/-10%'     = 'SMC_0402R'                | '(SMC_0402R_C)'                                 | 'CAP, 15NF, +/-10%, 16V, X7R, 0402'                                               | 'NFND'    
 'CL1003090A'     | '47NF'    | '+/-10%'     = 'SMC_0402R'                | '(SMC_0402R_C)'                                 | 'CAP, 47NF, +/-10%, 16V, X7R, 0402'                                               | 'NFND'    
 'CL1003091A'     | '6800PF'  | '+/-10%'     = 'SMC_0402R'                | '(SMC_0402R_C)'                                 | 'CAP, 6800PF, +/-10%, 16V, X7R, 0402'                                             | 'NFND'    
 'CL1003092A'     | '68NF'    | '+/-10%'     = 'SMC_0402R'                | '(SMC_0402R_C)'                                 | 'CAP, 68NF, +/-10%, 16V, X7R, 0402'                                               | 'NFND'    
 'G101-00013-01'  | '68NF'    | '+/-10%'     = 'SMC_0402R'                | '(SMC_0402R_C)'                                 | 'CAP, 68NF, +/-10%, 16V, X7R, 0402'                                               | 'NFND'    
 'CL1003093A'     | '1000PF'  | '+/-10%'     = 'SMC_0402R'                | '(SMC_0402R_C)'                                 | 'CAP, 1000PF, +/-10%, 25V, X7R, 0402'                                             | 'NFND'    
 'CL1003094A'     | '10NF'    | '+/-10%'     = 'SMC_0402R'                | '(SMC_0402R_C)'                                 | 'CAP, 10NF, +/-10%, 25V, X7R, 0402'                                               | 'NFND'    
 'CL1003095A'     | '15NF'    | '+/-10%'     = 'SMC_0402R'                | '(SMC_0402R_C)'                                 | 'CAP, 15NF, +/-10%, 25V, X7R, 0402'                                               | 'NFND'    
 'CL1003096A'     | '22NF'    | '+/-10%'     = 'SMC_0402R'                | '(SMC_0402R_C)'                                 | 'CAP, 22NF, +/-10%, 25V, X7R, 0402'                                               | 'NFND'    
 'CL1003097A'     | '3300PF'  | '+/-10%'     = 'SMC_0402R'                | '(SMC_0402R_C)'                                 | 'CAP, 3300PF, +/-10%, 25V, X7R, 0402'                                             | 'NFND'    
 'CL1003098A'     | '33NF'    | '+/-10%'     = 'SMC_0402R'                | '(SMC_0402R_C)'                                 | 'CAP, 33NF, +/-10%, 25V, X7R, 0402'                                               | 'NFND'    
 'CL1003099A'     | '4700PF'  | '+/-10%'     = 'SMC_0402R'                | '(SMC_0402R_C)'                                 | 'CAP, 4700PF, +/-10%, 25V, X7R, 0402'                                             | 'NFND'    
 'CL1003100A'     | '47NF'    | '+/-10%'     = 'SMC_0402R'                | '(SMC_0402R_C)'                                 | 'CAP, 47NF, +/-10%, 25V, X7R, 0402'                                               | 'NFND'    
 'CL1003101A'     | '6800PF'  | '+/-10%'     = 'SMC_0402R'                | '(SMC_0402R_C)'                                 | 'CAP, 6800PF, +/-10%, 25V, X7R, 0402'                                             | 'NFND'    
 'CL1003102A'     | '8200PF'  | '+/-10%'     = 'SMC_0402R'                | '(SMC_0402R_C)'                                 | 'CAP, 8200PF, +/-10%, 25V, X7R, 0402'                                             | 'NFND'    
 'CL1003103A'     | '2200PF'  | '+/-10%'     = 'SMC_0402R'                | '(SMC_0402R_C)'                                 | 'CAP, 2200PF, +/-10%, 50V, X7R, 0402'                                             | 'NFND'    
 'CL1003104A'     | '3300PF'  | '+/-10%'     = 'SMC_0402R'                | '(SMC_0402R_C)'                                 | 'CAP, 3300PF, +/-10%, 50V, X7R, 0402'                                             | 'NFND'    
 'CL1003105A'     | '470PF'   | '+/-10%'     = 'SMC_0402R'                | '(SMC_0402R_C)'                                 | 'CAP, 470PF, +/-10%, 50V, X7R, 0402'                                              | 'NFND'    
 'CL1003106A'     | '680PF'   | '+/-10%'     = 'SMC_0402R'                | '(SMC_0402R_C)'                                 | 'CAP, 680PF, +/-10%, 50V, X7R, 0402'                                              | 'NFND'    
 'CL1003107A'     | '6800PF'  | '+/-10%'     = 'SMC_0402R'                | '(SMC_0402R_C)'                                 | 'CAP, 6800PF, +/-10%, 50V, X7R, 0402'                                             | 'NFND'    
 'CL1003108A'     | '820PF'   | '+/-10%'     = 'SMC_0402R'                | '(SMC_0402R_C)'                                 | 'CAP, 820PF, +/-10%, 50V, X7R, 0402'                                              | 'NFND'    
 'CL1003109A'     | '1UF'     | '-20/+80%'    = 'SMC_0402R'                | '(SMC_0402R_C)'                                 | 'CAP, 1UF, -20/+80%, 6.3V, Y5V, 0402'                                             | 'NFND'    
 'CL1003110A'     | '220NF'   | '-20/+80%'    = 'SMC_0402R'                | '(SMC_0402R_C)'                                 | 'CAP, 220NF, -20/+80%, 10V, Y5V, 0402'                                            | 'NFND'    
 'CL1003111A'     | '470NF'   | '-20/+80%'    = 'SMC_0402R'                | '(SMC_0402R_C)'                                 | 'CAP, 470NF, -20/+80%, 10V, Y5V, 0402'                                            | 'NFND'    
 'CL1003112A'     | '220NF'   | '-20/+80%'    = 'SMC_0402R'                | '(SMC_0402R_C)'                                 | 'CAP, 220NF, -20/+80%, 16V, Y5V, 0402'                                            | 'NFND'    
 'CL1003113A'     | '100NF'   | '-20/+80%'    = 'SMC_0402R'                | '(SMC_0402R_C)'                                 | 'CAP, 100NF, -20/+80%, 25V, Y5V, 0402'                                            | 'NFND'    
 'CL1003114A'     | '10NF'    | '-20/+80%'    = 'SMC_0402R'                | '(SMC_0402R_C)'                                 | 'CAP, 10NF, -20/+80%, 50V, Y5V, 0402'                                             | 'NFND'    
 'CL1003115A'     | '1PF'     | '+/-0.25PF'    = 'SMC_0603R'                | '(SMC_0603R)'                                   | 'CAP, 1PF, +/-0.25PF, 50V, C0G, 0603'                                             | 'NFND'    
 'CL1003116A'     | '2PF'     | '+/-0.25PF'    = 'SMC_0603R'                | '(SMC_0603R)'                                   | 'CAP, 2PF, +/-0.25PF, 50V, C0G, 0603'                                             | 'NFND'    
 'CL1003117A'     | '3PF'     | '+/-0.25PF'    = 'SMC_0603R'                | '(SMC_0603R)'                                   | 'CAP, 3PF, +/-0.25PF, 50V, C0G, 0603'                                             | 'NFND'    
 'CL1003118A'     | '4PF'     | '+/-0.25PF'    = 'SMC_0603R'                | '(SMC_0603R)'                                   | 'CAP, 4PF, +/-0.25PF, 50V, C0G, 0603'                                             | 'NFND'    
 'CL1003119A'     | '5PF'     | '+/-0.25PF'    = 'SMC_0603R'                | '(SMC_0603R)'                                   | 'CAP, 5PF, +/-0.25PF, 50V, C0G, 0603'                                             | 'NFND'    
 'CL1003120A'     | '6PF'     | '+/-0.5PF'    = 'SMC_0603R'                | '(SMC_0603R)'                                   | 'CAP, 6PF, +/-0.5PF, 50V, C0G, 0603'                                              | 'NFND'    
 'CL1003121A'     | '7PF'     | '+/-0.5PF'    = 'SMC_0603R'                | '(SMC_0603R)'                                   | 'CAP, 7PF, +/-0.5PF, 50V, C0G, 0603'                                              | 'NFND'    
 'CL1003122A'     | '8PF'     | '+/-0.5PF'    = 'SMC_0603R'                | '(SMC_0603R)'                                   | 'CAP, 8PF, +/-0.5PF, 50V, C0G, 0603'                                              | 'NFND'    
 'CL1003123A'     | '9PF'     | '+/-0.5PF'    = 'SMC_0603R'                | '(SMC_0603R)'                                   | 'CAP, 9PF, +/-0.5PF, 50V, C0G, 0603'                                              | 'NFND'    
 'CL1003124A'     | '0.5PF'   | '+/-0.25PF'    = 'SMC_0603R'                | '(SMC_0603R)'                                   | 'CAP, 0.5PF, +/-0.25PF, 50V, C0G, 0603'                                           | 'NFND'    
 'CL1003125A'     | '10PF'    | '+/-0.5PF'    = 'SMC_0603R'                | '(SMC_0603R)'                                   | 'CAP, 10PF, +/-0.5PF, 50V, C0G, 0603'                                             | 'NFND'    
 'CL1003126A'     | '1000PF'  | '+/-5%'      = 'SMC_0603R'                | '(SMC_0603R)'                                   | 'CAP, 1000PF, +/-5%, 50V, C0G, 0603'                                              | 'NFND'    
 'CL1003127A'     | '1200PF'  | '+/-5%'      = 'SMC_0603R'                | '(SMC_0603R)'                                   | 'CAP, 1200PF, +/-5%, 50V, C0G, 0603'                                              | 'NFND'    
 'G106-0A122-FJ'  | '1200PF'  | '+/-5%'      = 'SMC_0603R'                | '(SMC_0603R)'                                   | 'CAP, 1200PF, +/-5%, 50V, C0G, 0603'                                              | ''        
 'CL1003128A'     | '150PF'   | '+/-5%'      = 'SMC_0603R'                | '(SMC_0603R)'                                   | 'CAP, 150PF, +/-5%, 50V, C0G, 0603'                                               | 'NFND'    
 'CL1003129A'     | '180PF'   | '+/-5%'      = 'SMC_0603R'                | '(SMC_0603R)'                                   | 'CAP, 180PF, +/-5%, 50V, C0G, 0603'                                               | 'NFND'    
 'G106-0A181-FJ'  | '180PF'   | '+/-5%'      = 'SMC_0603R'                | '(SMC_0603R)'                                   | 'CAP, 180PF, +/-5%, 50V, C0G, 0603'                                               | 'NFND'    
 'CL1003130A'     | '1800PF'  | '+/-5%'      = 'SMC_0603R'                | '(SMC_0603R)'                                   | 'CAP, 1800PF, +/-5%, 50V, C0G, 0603'                                              | 'NFND'    
 'CL1003131A'     | '1.5PF'   | '+/-0.25PF'    = 'SMC_0603R'                | '(SMC_0603R)'                                   | 'CAP, 1.5PF, +/-0.25PF, 50V, C0G, 0603'                                           | 'NFND'    
 'CL1003132A'     | '2200PF'  | '+/-5%'      = 'SMC_0603R'                | '(SMC_0603R)'                                   | 'CAP, 2200PF, +/-5%, 50V, C0G, 0603'                                              | 'NFND'    
 'G106-0A222-FJ'  | '2200PF'  | '+/-5%'      = 'SMC_0603R'                | '(SMC_0603R)'                                   | 'CAP, 2200PF, +/-5%, 50V, C0G, 0603'                                              | ''        
 'CL1003133A'     | '270PF'   | '+/-5%'      = 'SMC_0603R'                | '(SMC_0603R)'                                   | 'CAP, 270PF, +/-5%, 50V, C0G, 0603'                                               | 'NFND'    
 'CL1003134A'     | '2700PF'  | '+/-5%'      = 'SMC_0603R'                | '(SMC_0603R)'                                   | 'CAP, 2700PF, +/-5%, 50V, C0G, 0603'                                              | 'NFND'    
 'G106-0A272-FJ'  | '2700PF'  | '+/-5%'      = 'SMC_0603R'                | '(SMC_0603R)'                                   | 'CAP, 2700PF, +/-5%, 50V, C0G, 0603'                                              | ''        
 'CL1003135A'     | '2.2PF'   | '+/-0.25PF'    = 'SMC_0603R'                | '(SMC_0603R)'                                   | 'CAP, 2.2PF, +/-0.25PF, 50V, C0G, 0603'                                           | 'NFND'    
 'CL1003136A'     | '3300PF'  | '+/-5%'      = 'SMC_0603R'                | '(SMC_0603R)'                                   | 'CAP, 3300PF, +/-5%, 50V, C0G, 0603'                                              | 'NFND'    
 'G106-0A332-FJ'  | '3300PF'  | '+/-5%'      = 'SMC_0603R'                | '(SMC_0603R)'                                   | 'CAP, 3300PF, +/-5%, 50V, C0G, 0603'                                              | ''        
 'CL1003137A'     | '390PF'   | '+/-5%'      = 'SMC_0603R'                | '(SMC_0603R)'                                   | 'CAP, 390PF, +/-5%, 50V, C0G, 0603'                                               | 'NFND'    
 'CL1003138A'     | '3.3PF'   | '+/-0.25PF'    = 'SMC_0603R'                | '(SMC_0603R)'                                   | 'CAP, 3.3PF, +/-0.25PF, 50V, C0G, 0603'                                           | 'NFND'    
 'CL1003139A'     | '470PF'   | '+/-5%'      = 'SMC_0603R'                | '(SMC_0603R)'                                   | 'CAP, 470PF, +/-5%, 50V, C0G, 0603'                                               | 'NFND'    
 'CL1003140A'     | '4.7PF'   | '+/-0.25PF'    = 'SMC_0603R'                | '(SMC_0603R)'                                   | 'CAP, 4.7PF, +/-0.25PF, 50V, C0G, 0603'                                           | 'NFND'    
 'CL1003141A'     | '56PF'    | '+/-5%'      = 'SMC_0603R'                | '(SMC_0603R)'                                   | 'CAP, 56PF, +/-5%, 50V, C0G, 0603'                                                | 'NFND'    
 'CL1003142A'     | '6.8PF'   | '+/-0.5PF'    = 'SMC_0603R'                | '(SMC_0603R)'                                   | 'CAP, 6.8PF, +/-0.5PF, 50V, C0G, 0603'                                            | 'NFND'    
 'CL1003143A'     | '82PF'    | '+/-5%'      = 'SMC_0603R'                | '(SMC_0603R)'                                   | 'CAP, 82PF, +/-5%, 50V, C0G, 0603'                                                | 'NFND'    
 'CL1003144A'     | '820PF'   | '+/-5%'      = 'SMC_0603R'                | '(SMC_0603R)'                                   | 'CAP, 820PF, +/-5%, 50V, C0G, 0603'                                               | 'NFND'    
 'CL1003145A'     | '8.2PF'   | '+/-0.5PF'    = 'SMC_0603R'                | '(SMC_0603R)'                                   | 'CAP, 8.2PF, +/-0.5PF, 50V, C0G, 0603'                                            | 'NFND'    
 'CL1003146A'     | '100PF'   | '+/-5%'      = 'SMC_0603R'                | '(SMC_0603R)'                                   | 'CAP, 100PF, +/-5%, 100V, C0G, 0603'                                              | 'NFND'    
 'CL1003147A'     | '1000PF'  | '+/-5%'      = 'SMC_0603R'                | '(SMC_0603R)'                                   | 'CAP, 1000PF, +/-5%, 100V, C0G, 0603'                                             | 'NFND'    
 'CL1003148A'     | '1200PF'  | '+/-5%'      = 'SMC_0603R'                | '(SMC_0603R)'                                   | 'CAP, 1200PF, +/-5%, 100V, C0G, 0603'                                             | 'NFND'    
 'CL1003149A'     | '220PF'   | '+/-5%'      = 'SMC_0603R'                | '(SMC_0603R)'                                   | 'CAP, 220PF, +/-5%, 100V, C0G, 0603'                                              | 'NFND'    
 'CL1003150A'     | '470PF'   | '+/-5%'      = 'SMC_0603R'                | '(SMC_0603R)'                                   | 'CAP, 470PF, +/-5%, 100V, C0G, 0603'                                              | 'NFND'    
 'CL1003151A'     | '680PF'   | '+/-5%'      = 'SMC_0603R'                | '(SMC_0603R)'                                   | 'CAP, 680PF, +/-5%, 100V, C0G, 0603'                                              | 'NFND'    
 'CL1003152A'     | '820PF'   | '+/-5%'      = 'SMC_0603R'                | '(SMC_0603R)'                                   | 'CAP, 820PF, +/-5%, 100V, C0G, 0603'                                              | 'NFND'    
 'CL1003153A'     | '100PF'   | '+/-5%'      = 'SMC_0603R'                | '(SMC_0603R)'                                   | 'CAP, 100PF, +/-5%, 250V, C0G, 0603'                                              | 'NFND'    
 'CL1003154A'     | '220PF'   | '+/-5%'      = 'SMC_0603R'                | '(SMC_0603R)'                                   | 'CAP, 220PF, +/-5%, 250V, C0G, 0603'                                              | 'NFND'    
 'CL1003155A'     | '470PF'   | '+/-5%'      = 'SMC_0603R'                | '(SMC_0603R)'                                   | 'CAP, 470PF, +/-5%, 250V, C0G, 0603'                                              | 'NFND'    
 'CL1003156A'     | '680PF'   | '+/-5%'      = 'SMC_0603R'                | '(SMC_0603R)'                                   | 'CAP, 680PF, +/-5%, 250V, C0G, 0603'                                              | 'NFND'    
 'CL1003157A'     | '1UF'     | '+/-10%'     = 'SMC_0603R'                | '(SMC_0603R)'                                   | 'CAP, 1UF, +/-10%, 6.3V, X5R, 0603'                                               | 'NFND'    
 'CL1003158A'     | '3.3UF'   | '+/-10%'     = 'SMC_0603R'                | '(SMC_0603R)'                                   | 'CAP, 3.3UF, +/-10%, 6.3V, X5R, 0603'                                             | 'NFND'    
 'CL1003159A'     | '4.7UF'   | '+/-10%'     = 'SMC_0603R'                | '(SMC_0603R)'                                   | 'CAP, 4.7UF, +/-10%, 6.3V, X5R, 0603'                                             | 'NFND'    
 'G101-00018-01'  | '4.7UF'   | '+/-10%'     = 'SMC_0603R'                | '(SMC_0603R)'                                   | 'CAP, 4.7UF, +/-10%, 6.3V, X5R, 0603'                                             | 'NFND'    
 'CL1003160A'     | '1UF'     | '+/-10%'     = 'SMC_0603R'                | '(SMC_0603R)'                                   | 'CAP, 1UF, +/-10%, 10V, X5R, 0603'                                                | 'NFND'    
 'CL1003161A'     | '220NF'   | '+/-10%'     = 'SMC_0603R'                | '(SMC_0603R)'                                   | 'CAP, 220NF, +/-10%, 10V, X5R, 0603'                                              | 'NFND'    
 'CL1003162A'     | '2.2UF'   | '+/-10%'     = 'SMC_0603R'                | '(SMC_0603R)'                                   | 'CAP, 2.2UF, +/-10%, 10V, X5R, 0603'                                              | 'NFND'    
 'G101-00027-01'  | '2.2UF'   | '+/-10%'     = 'SMC_0603R'                | '(SMC_0603R)'                                   | 'CAP, 2.2UF, +/-10%, 10V, X5R, 0603'                                              | 'NFND'    
 'CL1003163A'     | '330NF'   | '+/-10%'     = 'SMC_0603R'                | '(SMC_0603R)'                                   | 'CAP, 330NF, +/-10%, 10V, X5R, 0603'                                              | 'NFND'    
 'CL1003164A'     | '470NF'   | '+/-10%'     = 'SMC_0603R'                | '(SMC_0603R)'                                   | 'CAP, 470NF, +/-10%, 10V, X5R, 0603'                                              | 'NFND'    
 'CL1003165A'     | '680NF'   | '+/-10%'     = 'SMC_0603R'                | '(SMC_0603R)'                                   | 'CAP, 680NF, +/-10%, 10V, X5R, 0603'                                              | 'NFND'    
 'CL1003166A'     | '220NF'   | '+/-10%'     = 'SMC_0603R'                | '(SMC_0603R)'                                   | 'CAP, 220NF, +/-10%, 16V, X5R, 0603'                                              | 'NFND'    
 'CL1003167A'     | '2.2UF'   | '+/-10%'     = 'SMC_0603R'                | '(SMC_0603R)'                                   | 'CAP, 2.2UF, +/-10%, 16V, X5R, 0603'                                              | 'NFND'    
 'CL1003168A'     | '330NF'   | '+/-10%'     = 'SMC_0603R'                | '(SMC_0603R)'                                   | 'CAP, 330NF, +/-10%, 16V, X5R, 0603'                                              | 'NFND'    
 'CL1003169A'     | '470NF'   | '+/-10%'     = 'SMC_0603R'                | '(SMC_0603R)'                                   | 'CAP, 470NF, +/-10%, 16V, X5R, 0603'                                              | 'NFND'    
 'CL1003170A'     | '680NF'   | '+/-10%'     = 'SMC_0603R'                | '(SMC_0603R)'                                   | 'CAP, 680NF, +/-10%, 16V, X5R, 0603'                                              | 'NFND'    
 'CL1003171A'     | '220NF'   | '+/-10%'     = 'SMC_0603R'                | '(SMC_0603R)'                                   | 'CAP, 220NF, +/-10%, 25V, X5R, 0603'                                              | 'NFND'    
 'CL1003172A'     | '330NF'   | '+/-10%'     = 'SMC_0603R'                | '(SMC_0603R)'                                   | 'CAP, 330NF, +/-10%, 25V, X5R, 0603'                                              | 'NFND'    
 'CL1003173A'     | '470NF'   | '+/-10%'     = 'SMC_0603R'                | '(SMC_0603R)'                                   | 'CAP, 470NF, +/-10%, 25V, X5R, 0603'                                              | 'NFND'    
 'CL1003174A'     | '10NF'    | '+/-10%'     = 'SMC_0603R'                | '(SMC_0603R)'                                   | 'CAP, 10NF, +/-10%, 50V, X5R, 0603'                                               | 'NFND'    
 'CL1003175A'     | '100NF'   | '+/-10%'     = 'SMC_0603R'                | '(SMC_0603R)'                                   | 'CAP, 100NF, +/-10%, 50V, X5R, 0603'                                              | 'NFND'    
 'G106-0C104-FK'  | '100NF'   | '+/-10%'     = 'SMC_0603R'                | '(SMC_0603R)'                                   | 'CAP, 100NF, +/-10%, 50V, X5R, 0603'                                              | 'NFND'    
 'CL1003176A'     | '22NF'    | '+/-10%'     = 'SMC_0603R'                | '(SMC_0603R)'                                   | 'CAP, 22NF, +/-10%, 50V, X5R, 0603'                                               | ''        
 'G106-0C223-FK'  | '22NF'    | '+/-10%'     = 'SMC_0603R'                | '(SMC_0603R)'                                   | 'CAP, 22NF, +/-10%, 50V, X5R, 0603'                                               | 'NFND'    
 'CL1003177A'     | '33NF'    | '+/-10%'     = 'SMC_0603R'                | '(SMC_0603R)'                                   | 'CAP, 33NF, +/-10%, 50V, X5R, 0603'                                               | 'NFND'    
 'G106-0C333-FK'  | '33NF'    | '+/-10%'     = 'SMC_0603R'                | '(SMC_0603R)'                                   | 'CAP, 33NF, +/-10%, 50V, X5R, 0603'                                               | 'NFND'    
 'CL1003178A'     | '47NF'    | '+/-10%'     = 'SMC_0603R'                | '(SMC_0603R)'                                   | 'CAP, 47NF, +/-10%, 50V, X5R, 0603'                                               | 'NFND'    
 'G106-0C473-FK'  | '47NF'    | '+/-10%'     = 'SMC_0603R'                | '(SMC_0603R)'                                   | 'CAP, 47NF, +/-10%, 50V, X5R, 0603'                                               | 'NFND'    
 'CL1003179A'     | '68NF'    | '+/-10%'     = 'SMC_0603R'                | '(SMC_0603R)'                                   | 'CAP, 68NF, +/-10%, 50V, X5R, 0603'                                               | 'NFND'    
 'G106-0C683-FK'  | '68NF'    | '+/-10%'     = 'SMC_0603R'                | '(SMC_0603R)'                                   | 'CAP, 68NF, +/-10%, 50V, X5R, 0603'                                               | 'NFND'    
 'CL1003180A'     | '1UF'     | '+/-10%'     = 'SMC_0603R'                | '(SMC_0603R)'                                   | 'CAP, 1UF, +/-10%, 6.3V, X7R, 0603'                                               | 'NFND'    
 'G101-00012-01'  | '1UF'     | '+/-10%'     = 'SMC_0603R'                | '(SMC_0603R)'                                   | 'CAP, 1UF, +/-10%, 6.3V, X7R, 0603'                                               | 'NFND'    
 'CL1003181A'     | '1UF'     | '+/-10%'     = 'SMC_0603R'                | '(SMC_0603R)'                                   | 'CAP, 1UF, +/-10%, 10V, X7R, 0603'                                                | 'NFND'    
 'CL1003182A'     | '220NF'   | '+/-10%'     = 'SMC_0603R'                | '(SMC_0603R)'                                   | 'CAP, 220NF, +/-10%, 10V, X7R, 0603'                                              | 'NFND'    
 'CL1003183A'     | '330NF'   | '+/-10%'     = 'SMC_0603R'                | '(SMC_0603R)'                                   | 'CAP, 330NF, +/-10%, 10V, X7R, 0603'                                              | 'NFND'    
 'CL1003184A'     | '470NF'   | '+/-10%'     = 'SMC_0603R'                | '(SMC_0603R)'                                   | 'CAP, 470NF, +/-10%, 10V, X7R, 0603'                                              | 'NFND'    
 'CL1003185A'     | '100NF'   | '+/-10%'     = 'SMC_0603R'                | '(SMC_0603R)'                                   | 'CAP, 100NF, +/-10%, 16V, X7R, 0603'                                              | 'NFND'    
 'G106-0B104-DK'  | '100NF'   | '+/-10%'     = 'SMC_0603R'                | '(SMC_0603R)'                                   | 'CAP, 100NF, +/-10%, 16V, X7R, 0603'                                              | 'NFND'    
 'CL1003186A'     | '1UF'     | '+/-10%'     = 'SMC_0603R'                | '(SMC_0603R)'                                   | 'CAP, 1UF, +/-10%, 16V, X7R, 0603'                                                | 'NFND'    
 'CL1003187A'     | '22NF'    | '+/-10%'     = 'SMC_0603R'                | '(SMC_0603R)'                                   | 'CAP, 22NF, +/-10%, 16V, X7R, 0603'                                               | 'NFND'    
 'CL1003188A'     | '220NF'   | '+/-10%'     = 'SMC_0603R'                | '(SMC_0603R)'                                   | 'CAP, 220NF, +/-10%, 16V, X7R, 0603'                                              | 'NFND'    
 'CL1003189A'     | '33NF'    | '+/-10%'     = 'SMC_0603R'                | '(SMC_0603R)'                                   | 'CAP, 33NF, +/-10%, 16V, X7R, 0603'                                               | 'NFND'    
 'CL1003190A'     | '330NF'   | '+/-10%'     = 'SMC_0603R'                | '(SMC_0603R)'                                   | 'CAP, 330NF, +/-10%, 16V, X7R, 0603'                                              | 'NFND'    
 'CL1003191A'     | '47NF'    | '+/-10%'     = 'SMC_0603R'                | '(SMC_0603R)'                                   | 'CAP, 47NF, +/-10%, 16V, X7R, 0603'                                               | 'NFND'    
 'CL1003192A'     | '470NF'   | '+/-10%'     = 'SMC_0603R'                | '(SMC_0603R)'                                   | 'CAP, 470NF, +/-10%, 16V, X7R, 0603'                                              | 'NFND'    
 'CL1003193A'     | '68NF'    | '+/-10%'     = 'SMC_0603R'                | '(SMC_0603R)'                                   | 'CAP, 68NF, +/-10%, 16V, X7R, 0603'                                               | 'NFND'    
 'CL1003194A'     | '680NF'   | '+/-10%'     = 'SMC_0603R'                | '(SMC_0603R)'                                   | 'CAP, 680NF, +/-10%, 16V, X7R, 0603'                                              | 'NFND'    
 'CL1003195A'     | '10NF'    | '+/-10%'     = 'SMC_0603R'                | '(SMC_0603R)'                                   | 'CAP, 10NF, +/-10%, 25V, X7R, 0603'                                               | 'NFND'    
 'CL1003196A'     | '100NF'   | '+/-10%'     = 'SMC_0603R'                | '(SMC_0603R)'                                   | 'CAP, 100NF, +/-10%, 25V, X7R, 0603'                                              | 'NFND'    
 'CL1003197A'     | '22NF'    | '+/-10%'     = 'SMC_0603R'                | '(SMC_0603R)'                                   | 'CAP, 22NF, +/-10%, 25V, X7R, 0603'                                               | 'NFND'    
 'CL1003198A'     | '220NF'   | '+/-10%'     = 'SMC_0603R'                | '(SMC_0603R)'                                   | 'CAP, 220NF, +/-10%, 25V, X7R, 0603'                                              | 'NFND'    
 'CL1003199A'     | '33NF'    | '+/-10%'     = 'SMC_0603R'                | '(SMC_0603R)'                                   | 'CAP, 33NF, +/-10%, 25V, X7R, 0603'                                               | 'NFND'    
 'CL1003200A'     | '47NF'    | '+/-10%'     = 'SMC_0603R'                | '(SMC_0603R)'                                   | 'CAP, 47NF, +/-10%, 25V, X7R, 0603'                                               | 'NFND'    
 'CL1003201A'     | '68NF'    | '+/-10%'     = 'SMC_0603R'                | '(SMC_0603R)'                                   | 'CAP, 68NF, +/-10%, 25V, X7R, 0603'                                               | 'NFND'    
 'CL1003202A'     | '1000PF'  | '+/-10%'     = 'SMC_0603R'                | '(SMC_0603R)'                                   | 'CAP, 1000PF, +/-10%, 50V, X7R, 0603'                                             | 'NFND'    
 'CL1003203A'     | '100NF'   | '+/-10%'     = 'SMC_0603R'                | '(SMC_0603R)'                                   | 'CAP, 100NF, +/-10%, 50V, X7R, 0603'                                              | 'NFND'    
 'CL1003204A'     | '2200PF'  | '+/-10%'     = 'SMC_0603R'                | '(SMC_0603R)'                                   | 'CAP, 2200PF, +/-10%, 50V, X7R, 0603'                                             | 'NFND'    
 'CL1003205A'     | '3300PF'  | '+/-10%'     = 'SMC_0603R'                | '(SMC_0603R)'                                   | 'CAP, 3300PF, +/-10%, 50V, X7R, 0603'                                             | 'NFND'    
 'CL1003206A'     | '470PF'   | '+/-10%'     = 'SMC_0603R'                | '(SMC_0603R)'                                   | 'CAP, 470PF, +/-10%, 50V, X7R, 0603'                                              | 'NFND'    
 'CL1003207A'     | '4700PF'  | '+/-10%'     = 'SMC_0603R'                | '(SMC_0603R)'                                   | 'CAP, 4700PF, +/-10%, 50V, X7R, 0603'                                             | 'NFND'    
 'CL1003208A'     | '47NF'    | '+/-10%'     = 'SMC_0603R'                | '(SMC_0603R)'                                   | 'CAP, 47NF, +/-10%, 50V, X7R, 0603'                                               | 'NFND'    
 'CL1003209A'     | '680PF'   | '+/-10%'     = 'SMC_0603R'                | '(SMC_0603R)'                                   | 'CAP, 680PF, +/-10%, 50V, X7R, 0603'                                              | 'NFND'    
 'CL1003210A'     | '6800PF'  | '+/-10%'     = 'SMC_0603R'                | '(SMC_0603R)'                                   | 'CAP, 6800PF, +/-10%, 50V, X7R, 0603'                                             | 'NFND'    
 'G106-0B682-FK'  | '6800PF'  | '+/-10%'     = 'SMC_0603R'                | '(SMC_0603R)'                                   | 'CAP, 6800PF, +/-10%, 50V, X7R, 0603'                                             | 'NFND'    
 'CL1003211A'     | '1000PF'  | '+/-10%'     = 'SMC_0603R'                | '(SMC_0603R)'                                   | 'CAP, 1000PF, +/-10%, 100V, X7R, 0603'                                            | 'NFND'    
 'CL1003212A'     | '10NF'    | '+/-10%'     = 'SMC_0603R'                | '(SMC_0603R)'                                   | 'CAP, 10NF, +/-10%, 100V, X7R, 0603'                                              | 'NFND'    
 'CL1003213A'     | '1500PF'  | '+/-10%'     = 'SMC_0603R'                | '(SMC_0603R)'                                   | 'CAP, 1500PF, +/-10%, 100V, X7R, 0603'                                            | 'NFND'    
 'CL1003214A'     | '2200PF'  | '+/-10%'     = 'SMC_0603R'                | '(SMC_0603R)'                                   | 'CAP, 2200PF, +/-10%, 100V, X7R, 0603'                                            | 'NFND'    
 'CL1003215A'     | '22NF'    | '+/-10%'     = 'SMC_0603R'                | '(SMC_0603R)'                                   | 'CAP, 22NF, +/-10%, 100V, X7R, 0603'                                              | 'NFND'    
 'CL1003216A'     | '3300PF'  | '+/-10%'     = 'SMC_0603R'                | '(SMC_0603R)'                                   | 'CAP, 3300PF, +/-10%, 100V, X7R, 0603'                                            | 'NFND'    
 'CL1003217A'     | '4700PF'  | '+/-10%'     = 'SMC_0603R'                | '(SMC_0603R)'                                   | 'CAP, 4700PF, +/-10%, 100V, X7R, 0603'                                            | 'NFND'    
 'CL1003218A'     | '10UF'    | '-20/+80%'    = 'SMC_0603R'                | '(SMC_0603R)'                                   | 'CAP, 10UF, -20/+80%, 6.3V, Y5V, 0603'                                            | 'NFND'    
 'CL1003219A'     | '4.7UF'   | '-20/+80%'    = 'SMC_0603R'                | '(SMC_0603R)'                                   | 'CAP, 4.7UF, -20/+80%, 6.3V, Y5V, 0603'                                           | 'NFND'    
 'CL1003220A'     | '100NF'   | '-20/+80%'    = 'SMC_0603R'                | '(SMC_0603R)'                                   | 'CAP, 100NF, -20/+80%, 16V, Y5V, 0603'                                            | 'NFND'    
 'CL1003221A'     | '1UF'     | '-20/+80%'    = 'SMC_0603R'                | '(SMC_0603R)'                                   | 'CAP, 1UF, -20/+80%, 16V, Y5V, 0603'                                              | 'NFND'    
 'CL1003222A'     | '220NF'   | '-20/+80%'    = 'SMC_0603R'                | '(SMC_0603R)'                                   | 'CAP, 220NF, -20/+80%, 16V, Y5V, 0603'                                            | 'NFND'    
 'CL1003223A'     | '2.2UF'   | '-20/+80%'    = 'SMC_0603R'                | '(SMC_0603R)'                                   | 'CAP, 2.2UF, -20/+80%, 16V, Y5V, 0603'                                            | 'NFND'    
 'CL1003224A'     | '470NF'   | '-20/+80%'    = 'SMC_0603R'                | '(SMC_0603R)'                                   | 'CAP, 470NF, -20/+80%, 16V, Y5V, 0603'                                            | 'NFND'    
 'CL1003225A'     | '1UF'     | '-20/+80%'    = 'SMC_0603R'                | '(SMC_0603R)'                                   | 'CAP, 1UF, -20/+80%, 25V, Y5V, 0603'                                              | 'NFND'    
 'CL1003226A'     | '10NF'    | '-20/+80%'    = 'SMC_0603R'                | '(SMC_0603R)'                                   | 'CAP, 10NF, -20/+80%, 50V, Y5V, 0603'                                             | 'NFND'    
 'CL1003227A'     | '100NF'   | '-20/+80%'    = 'SMC_0603R'                | '(SMC_0603R)'                                   | 'CAP, 100NF, -20/+80%, 50V, Y5V, 0603'                                            | 'NFND'    
 'CL1003228A'     | '22NF'    | '-20/+80%'    = 'SMC_0603R'                | '(SMC_0603R)'                                   | 'CAP, 22NF, -20/+80%, 50V, Y5V, 0603'                                             | 'NFND'    
 'CL1003229A'     | '220NF'   | '-20/+80%'    = 'SMC_0603R'                | '(SMC_0603R)'                                   | 'CAP, 220NF, -20/+80%, 50V, Y5V, 0603'                                            | 'NFND'    
 'CL1003230A'     | '47NF'    | '-20/+80%'    = 'SMC_0603R'                | '(SMC_0603R)'                                   | 'CAP, 47NF, -20/+80%, 50V, Y5V, 0603'                                             | 'NFND'    
 'CL1003231A'     | '470NF'   | '-20/+80%'    = 'SMC_0603R'                | '(SMC_0603R)'                                   | 'CAP, 470NF, -20/+80%, 50V, Y5V, 0603'                                            | 'NFND'    
 'CL1003232A'     | '10NF'    | '+/-5%'      = 'SMC_0805R'                | '(SMC_0805R)'                                   | 'CAP, 10NF, +/-5%, 50V, C0G, 0805'                                                | 'NFND'    
 'CL1003233A'     | '3300PF'  | '+/-5%'      = 'SMC_0805R'                | '(SMC_0805R)'                                   | 'CAP, 3300PF, +/-5%, 50V, C0G, 0805'                                              | 'NFND'    
 'CL1003234A'     | '4700PF'  | '+/-5%'      = 'SMC_0805R'                | '(SMC_0805R)'                                   | 'CAP, 4700PF, +/-5%, 50V, C0G, 0805'                                              | 'NFND'    
 'CL1003235A'     | '6800PF'  | '+/-5%'      = 'SMC_0805R'                | '(SMC_0805R)'                                   | 'CAP, 6800PF, +/-5%, 50V, C0G, 0805'                                              | 'NFND'    
 'CL1003236A'     | '1000PF'  | '+/-5%'      = 'SMC_0805R'                | '(SMC_0805R)'                                   | 'CAP, 1000PF, +/-5%, 100V, C0G, 0805'                                             | 'NFND'    
 'CL1003237A'     | '1500PF'  | '+/-5%'      = 'SMC_0805R'                | '(SMC_0805R)'                                   | 'CAP, 1500PF, +/-5%, 100V, C0G, 0805'                                             | 'NFND'    
 'CL1003238A'     | '2200PF'  | '+/-5%'      = 'SMC_0805R'                | '(SMC_0805R)'                                   | 'CAP, 2200PF, +/-5%, 100V, C0G, 0805'                                             | 'NFND'    
 'CL1003239A'     | '3300PF'  | '+/-5%'      = 'SMC_0805R'                | '(SMC_0805R)'                                   | 'CAP, 3300PF, +/-5%, 100V, C0G, 0805'                                             | 'NFND'    
 'CL1003240A'     | '4700PF'  | '+/-5%'      = 'SMC_0805R'                | '(SMC_0805R)'                                   | 'CAP, 4700PF, +/-5%, 100V, C0G, 0805'                                             | 'NFND'    
 'CL1003241A'     | '1000PF'  | '+/-5%'      = 'SMC_0805R'                | '(SMC_0805R)'                                   | 'CAP, 1000PF, +/-5%, 250V, C0G, 0805'                                             | 'NFND'    
 'CL1003242A'     | '1500PF'  | '+/-5%'      = 'SMC_0805R'                | '(SMC_0805R)'                                   | 'CAP, 1500PF, +/-5%, 250V, C0G, 0805'                                             | 'NFND'    
 'CL1003243A'     | '2200PF'  | '+/-5%'      = 'SMC_0805R'                | '(SMC_0805R)'                                   | 'CAP, 2200PF, +/-5%, 250V, C0G, 0805'                                             | 'NFND'    
 'CL1003244A'     | '2700PF'  | '+/-5%'      = 'SMC_0805R'                | '(SMC_0805R)'                                   | 'CAP, 2700PF, +/-5%, 250V, C0G, 0805'                                             | 'NFND'    
 'CL1003245A'     | '2.2UF'   | '+/-10%'     = 'SMC_0805R'                | '(SMC_0805R)'                                   | 'CAP, 2.2UF, +/-10%, 6.3V, X5R, 0805'                                             | 'NFND'    
 'CL1003246A'     | '4.7UF'   | '+/-10%'     = 'SMC_0805R'                | '(SMC_0805R)'                                   | 'CAP, 4.7UF, +/-10%, 6.3V, X5R, 0805'                                             | 'NFND'    
 'CL1003247A'     | '6.8UF'   | '+/-10%'     = 'SMC_0805R'                | '(SMC_0805R)'                                   | 'CAP, 6.8UF, +/-10%, 6.3V, X5R, 0805'                                             | 'NFND'    
 'CL1003248A'     | '1UF'     | '+/-10%'     = 'SMC_0805R'                | '(SMC_0805R)'                                   | 'CAP, 1UF, +/-10%, 10V, X5R, 0805'                                                | 'NFND'    
 'CL1003249A'     | '10UF'    | '+/-20%'     = 'SMC_0805R'                | '(SMC_0805R)'                                   | 'CAP, 10UF, +/-20%, 10V, X5R, 0805'                                               | 'NFND'    
 'CL1003250A'     | '2.2UF'   | '+/-10%'     = 'SMC_0805R'                | '(SMC_0805R)'                                   | 'CAP, 2.2UF, +/-10%, 10V, X5R, 0805'                                              | 'NFND'    
 'CL1003251A'     | '3.3UF'   | '+/-10%'     = 'SMC_0805R'                | '(SMC_0805R)'                                   | 'CAP, 3.3UF, +/-10%, 10V, X5R, 0805'                                              | 'NFND'    
 'CL1003252A'     | '4.7UF'   | '+/-10%'     = 'SMC_0805R'                | '(SMC_0805R)'                                   | 'CAP, 4.7UF, +/-10%, 10V, X5R, 0805'                                              | 'NFND'    
 'CL1003253A'     | '2.2UF'   | '+/-10%'     = 'SMC_0805R'                | '(SMC_0805R)'                                   | 'CAP, 2.2UF, +/-10%, 16V, X5R, 0805'                                              | 'NFND'    
 'CL1003254A'     | '4.7UF'   | '+/-10%'     = 'SMC_0805R'                | '(SMC_0805R)'                                   | 'CAP, 4.7UF, +/-10%, 16V, X5R, 0805'                                              | 'NFND'    
 'CL1003255A'     | '1UF'     | '+/-10%'     = 'SMC_0805R'                | '(SMC_0805R)'                                   | 'CAP, 1UF, +/-10%, 25V, X5R, 0805'                                                | 'NFND'    
 'CL1003256A'     | '2.2UF'   | '+/-10%'     = 'SMC_0805R'                | '(SMC_0805R)'                                   | 'CAP, 2.2UF, +/-10%, 25V, X5R, 0805'                                              | 'NFND'    
 'CL1003257A'     | '470NF'   | '+/-10%'     = 'SMC_0805R'                | '(SMC_0805R)'                                   | 'CAP, 470NF, +/-10%, 25V, X5R, 0805'                                              | 'NFND'    
 'CL1003258A'     | '4.7UF'   | '+/-10%'     = 'SMC_0805R'                | '(SMC_0805R)'                                   | 'CAP, 4.7UF, +/-10%, 25V, X5R, 0805'                                              | ''        
 'G101-00019-01'  | '4.7UF'   | '+/-10%'     = 'SMC_0805R'                | '(SMC_0805R)'                                   | 'CAP, 4.7UF, +/-10%, 25V, X5R, 0805'                                              | 'NFND'    
 'CL1003259A'     | '220NF'   | '+/-10%'     = 'SMC_0805R'                | '(SMC_0805R)'                                   | 'CAP, 220NF, +/-10%, 50V, X5R, 0805'                                              | 'NFND'    
 'CL1003260A'     | '1UF'     | '+/-10%'     = 'SMC_0805R'                | '(SMC_0805R)'                                   | 'CAP, 1UF, +/-10%, 10V, X7R, 0805'                                                | 'NFND'    
 'CL1003261A'     | '2.2UF'   | '+/-10%'     = 'SMC_0805R'                | '(SMC_0805R)'                                   | 'CAP, 2.2UF, +/-10%, 10V, X7R, 0805'                                              | 'NFND'    
 'CL1003262A'     | '4.7UF'   | '+/-10%'     = 'SMC_0805R'                | '(SMC_0805R)'                                   | 'CAP, 4.7UF, +/-10%, 10V, X7R, 0805'                                              | 'NFND'    
 'CL1003263A'     | '100NF'   | '+/-10%'     = 'SMC_0805R'                | '(SMC_0805R)'                                   | 'CAP, 100NF, +/-10%, 16V, X7R, 0805'                                              | 'NFND'    
 'CL1003264A'     | '150NF'   | '+/-10%'     = 'SMC_0805R'                | '(SMC_0805R)'                                   | 'CAP, 150NF, +/-10%, 16V, X7R, 0805'                                              | 'NFND'    
 'CL1003265A'     | '1.5UF'   | '+/-10%'     = 'SMC_0805R'                | '(SMC_0805R)'                                   | 'CAP, 1.5UF, +/-10%, 16V, X7R, 0805'                                              | 'NFND'    
 'CL1003266A'     | '220NF'   | '+/-10%'     = 'SMC_0805R'                | '(SMC_0805R)'                                   | 'CAP, 220NF, +/-10%, 16V, X7R, 0805'                                              | 'NFND'    
 'CL1003267A'     | '2.2UF'   | '+/-10%'     = 'SMC_0805R'                | '(SMC_0805R)'                                   | 'CAP, 2.2UF, +/-10%, 16V, X7R, 0805'                                              | 'NFND'    
 'CL1003268A'     | '470NF'   | '+/-10%'     = 'SMC_0805R'                | '(SMC_0805R)'                                   | 'CAP, 470NF, +/-10%, 16V, X7R, 0805'                                              | 'NFND'    
 'CL1003269A'     | '680NF'   | '+/-10%'     = 'SMC_0805R'                | '(SMC_0805R)'                                   | 'CAP, 680NF, +/-10%, 16V, X7R, 0805'                                              | 'NFND'    
 'CL1003270A'     | '100NF'   | '+/-10%'     = 'SMC_0805R'                | '(SMC_0805R)'                                   | 'CAP, 100NF, +/-10%, 25V, X7R, 0805'                                              | 'NFND'    
 'CL1003271A'     | '1UF'     | '+/-10%'     = 'SMC_0805R'                | '(SMC_0805R)'                                   | 'CAP, 1UF, +/-10%, 25V, X7R, 0805'                                                | 'NFND'    
 'CL1003272A'     | '150NF'   | '+/-10%'     = 'SMC_0805R'                | '(SMC_0805R)'                                   | 'CAP, 150NF, +/-10%, 25V, X7R, 0805'                                              | 'NFND'    
 'G107-0B154-EK'  | '150NF'   | '+/-10%'     = 'SMC_0805R'                | '(SMC_0805R)'                                   | 'CAP, 150NF, +/-10%, 25V, X7R, 0805'                                              | 'NFND'    
 'CL1003273A'     | '1.5UF'   | '+/-10%'     = 'SMC_0805R'                | '(SMC_0805R)'                                   | 'CAP, 1.5UF, +/-10%, 25V, X7R, 0805'                                              | 'NFND'    
 'CL1003274A'     | '220NF'   | '+/-10%'     = 'SMC_0805R'                | '(SMC_0805R)'                                   | 'CAP, 220NF, +/-10%, 25V, X7R, 0805'                                              | 'NFND'    
 'CL1003275A'     | '33NF'    | '+/-10%'     = 'SMC_0805R'                | '(SMC_0805R)'                                   | 'CAP, 33NF, +/-10%, 25V, X7R, 0805'                                               | 'NFND'    
 'CL1003276A'     | '330NF'   | '+/-10%'     = 'SMC_0805R'                | '(SMC_0805R)'                                   | 'CAP, 330NF, +/-10%, 25V, X7R, 0805'                                              | 'NFND'    
 'CL1003277A'     | '470NF'   | '+/-10%'     = 'SMC_0805R'                | '(SMC_0805R)'                                   | 'CAP, 470NF, +/-10%, 25V, X7R, 0805'                                              | 'NFND'    
 'CL1003278A'     | '680NF'   | '+/-10%'     = 'SMC_0805R'                | '(SMC_0805R)'                                   | 'CAP, 680NF, +/-10%, 25V, X7R, 0805'                                              | 'NFND'    
 'CL1003279A'     | '100NF'   | '+/-10%'     = 'SMC_0805R'                | '(SMC_0805R)'                                   | 'CAP, 100NF, +/-10%, 50V, X7R, 0805'                                              | 'NFND'    
 'CL1003280A'     | '150NF'   | '+/-10%'     = 'SMC_0805R'                | '(SMC_0805R)'                                   | 'CAP, 150NF, +/-10%, 50V, X7R, 0805'                                              | 'NFND'    
 'CL1003281A'     | '330NF'   | '+/-10%'     = 'SMC_0805R'                | '(SMC_0805R)'                                   | 'CAP, 330NF, +/-10%, 50V, X7R, 0805'                                              | 'NFND'    
 'CL1003282A'     | '47NF'    | '+/-10%'     = 'SMC_0805R'                | '(SMC_0805R)'                                   | 'CAP, 47NF, +/-10%, 50V, X7R, 0805'                                               | 'NFND'    
 'CL1003283A'     | '1000PF'  | '+/-10%'     = 'SMC_0805R'                | '(SMC_0805R)'                                   | 'CAP, 1000PF, +/-10%, 100V, X7R, 0805'                                            | 'NFND'    
 'CL1003284A'     | '10NF'    | '+/-10%'     = 'SMC_0805R'                | '(SMC_0805R)'                                   | 'CAP, 10NF, +/-10%, 100V, X7R, 0805'                                              | 'NFND'    
 'CL1003285A'     | '100NF'   | '+/-10%'     = 'SMC_0805R'                | '(SMC_0805R)'                                   | 'CAP, 100NF, +/-10%, 100V, X7R, 0805'                                             | 'NFND'    
 'CL1003286A'     | '15NF'    | '+/-10%'     = 'SMC_0805R'                | '(SMC_0805R)'                                   | 'CAP, 15NF, +/-10%, 100V, X7R, 0805'                                              | 'NFND'    
 'CL1003287A'     | '2200PF'  | '+/-10%'     = 'SMC_0805R'                | '(SMC_0805R)'                                   | 'CAP, 2200PF, +/-10%, 100V, X7R, 0805'                                            | 'NFND'    
 'CL1003288A'     | '22NF'    | '+/-10%'     = 'SMC_0805R'                | '(SMC_0805R)'                                   | 'CAP, 22NF, +/-10%, 100V, X7R, 0805'                                              | 'NFND'    
 'CL1003289A'     | '3300PF'  | '+/-10%'     = 'SMC_0805R'                | '(SMC_0805R)'                                   | 'CAP, 3300PF, +/-10%, 100V, X7R, 0805'                                            | 'NFND'    
 'CL1003290A'     | '33NF'    | '+/-10%'     = 'SMC_0805R'                | '(SMC_0805R)'                                   | 'CAP, 33NF, +/-10%, 100V, X7R, 0805'                                              | 'NFND'    
 'CL1003291A'     | '4700PF'  | '+/-10%'     = 'SMC_0805R'                | '(SMC_0805R)'                                   | 'CAP, 4700PF, +/-10%, 100V, X7R, 0805'                                            | 'NFND'    
 'CL1003292A'     | '47NF'    | '+/-10%'     = 'SMC_0805R'                | '(SMC_0805R)'                                   | 'CAP, 47NF, +/-10%, 100V, X7R, 0805'                                              | 'NFND'    
 'CL1003293A'     | '6800PF'  | '+/-10%'     = 'SMC_0805R'                | '(SMC_0805R)'                                   | 'CAP, 6800PF, +/-10%, 100V, X7R, 0805'                                            | 'NFND'    
 'CL1003294A'     | '68NF'    | '+/-10%'     = 'SMC_0805R'                | '(SMC_0805R)'                                   | 'CAP, 68NF, +/-10%, 100V, X7R, 0805'                                              | 'NFND'    
 'CL1003295A'     | '1000PF'  | '+/-10%'     = 'SMC_0805R'                | '(SMC_0805R)'                                   | 'CAP, 1000PF, +/-10%, 250V, X7R, 0805'                                            | 'NFND'    
 'CL1003296A'     | '10NF'    | '+/-10%'     = 'SMC_0805R'                | '(SMC_0805R)'                                   | 'CAP, 10NF, +/-10%, 250V, X7R, 0805'                                              | 'NFND'    
 'CL1003297A'     | '2200PF'  | '+/-10%'     = 'SMC_0805R'                | '(SMC_0805R)'                                   | 'CAP, 2200PF, +/-10%, 250V, X7R, 0805'                                            | 'NFND'    
 'CL1003298A'     | '22NF'    | '+/-10%'     = 'SMC_0805R'                | '(SMC_0805R)'                                   | 'CAP, 22NF, +/-10%, 250V, X7R, 0805'                                              | 'NFND'    
 'CL1003299A'     | '4700PF'  | '+/-10%'     = 'SMC_0805R'                | '(SMC_0805R)'                                   | 'CAP, 4700PF, +/-10%, 250V, X7R, 0805'                                            | 'NFND'    
 'CL1003300A'     | '6800PF'  | '+/-10%'     = 'SMC_0805R'                | '(SMC_0805R)'                                   | 'CAP, 6800PF, +/-10%, 250V, X7R, 0805'                                            | 'NFND'    
 'CL1003301A'     | '10UF'    | '-20/+80%'    = 'SMC_0805R'                | '(SMC_0805R)'                                   | 'CAP, 10UF, -20/+80%, 6.3V, Y5V, 0805'                                            | 'NFND'    
 'CL1003302A'     | '22UF'    | '-20/+80%'    = 'SMC_0805R'                | '(SMC_0805R)'                                   | 'CAP, 22UF, -20/+80%, 6.3V, Y5V, 0805'                                            | 'NFND'    
 'CL1003303A'     | '1UF'     | '-20/+80%'    = 'SMC_0805R'                | '(SMC_0805R)'                                   | 'CAP, 1UF, -20/+80%, 16V, Y5V, 0805'                                              | 'NFND'    
 'CL1003304A'     | '10UF'    | '-20/+80%'    = 'SMC_0805R'                | '(SMC_0805R)'                                   | 'CAP, 10UF, -20/+80%, 16V, Y5V, 0805'                                             | 'NFND'    
 'CL1003305A'     | '2.2UF'   | '-20/+80%'    = 'SMC_0805R'                | '(SMC_0805R)'                                   | 'CAP, 2.2UF, -20/+80%, 16V, Y5V, 0805'                                            | 'NFND'    
 'CL1003306A'     | '4.7UF'   | '-20/+80%'    = 'SMC_0805R'                | '(SMC_0805R)'                                   | 'CAP, 4.7UF, -20/+80%, 16V, Y5V, 0805'                                            | 'NFND'    
 'CL1003307A'     | '1UF'     | '-20/+80%'    = 'SMC_0805R'                | '(SMC_0805R)'                                   | 'CAP, 1UF, -20/+80%, 25V, Y5V, 0805'                                              | 'NFND'    
 'CL1003308A'     | '4.7UF'   | '-20/+80%'    = 'SMC_0805R'                | '(SMC_0805R)'                                   | 'CAP, 4.7UF, -20/+80%, 25V, Y5V, 0805'                                            | 'NFND'    
 'CL1003309A'     | '1UF'     | '-20/+80%'    = 'SMC_0805R'                | '(SMC_0805R)'                                   | 'CAP, 1UF, -20/+80%, 50V, Y5V, 0805'                                              | 'NFND'    
 'CL1003310A'     | '2.2UF'   | '-20/+80%'    = 'SMC_0805R'                | '(SMC_0805R)'                                   | 'CAP, 2.2UF, -20/+80%, 50V, Y5V, 0805'                                            | 'NFND'    
 'CL1003311A'     | '10NF'    | '+/-5%'      = 'SMC_1206R'                | '(SMC_1206R)'                                   | 'CAP, 10NF, +/-5%, 50V, C0G, 1206'                                                | 'NFND'    
 'CL1003312A'     | '15NF'    | '+/-5%'      = 'SMC_1206R'                | '(SMC_1206R)'                                   | 'CAP, 15NF, +/-5%, 50V, C0G, 1206'                                                | 'NFND'    
 'CL1003313A'     | '22NF'    | '+/-5%'      = 'SMC_1206R'                | '(SMC_1206R)'                                   | 'CAP, 22NF, +/-5%, 50V, C0G, 1206'                                                | 'NFND'    
 'CL1003314A'     | '33NF'    | '+/-5%'      = 'SMC_1206R'                | '(SMC_1206R)'                                   | 'CAP, 33NF, +/-5%, 50V, C0G, 1206'                                                | 'NFND'    
 'CL1003315A'     | '4700PF'  | '+/-5%'      = 'SMC_1206R'                | '(SMC_1206R)'                                   | 'CAP, 4700PF, +/-5%, 50V, C0G, 1206'                                              | 'NFND'    
 'CL1003316A'     | '6800PF'  | '+/-5%'      = 'SMC_1206R'                | '(SMC_1206R)'                                   | 'CAP, 6800PF, +/-5%, 50V, C0G, 1206'                                              | 'NFND'    
 'CL1003317A'     | '10NF'    | '+/-5%'      = 'SMC_1206R'                | '(SMC_1206R)'                                   | 'CAP, 10NF, +/-5%, 100V, C0G, 1206'                                               | 'NFND'    
 'CL1003318A'     | '4700PF'  | '+/-5%'      = 'SMC_1206R'                | '(SMC_1206R)'                                   | 'CAP, 4700PF, +/-5%, 250V, C0G, 1206'                                             | 'NFND'    
 'CL1003319A'     | '6800PF'  | '+/-5%'      = 'SMC_1206R'                | '(SMC_1206R)'                                   | 'CAP, 6800PF, +/-5%, 250V, C0G, 1206'                                             | 'NFND'    
 'CL1003320A'     | '100PF'   | '+/-5%'      = 'SMC_1206R'                | '(SMC_1206R)'                                   | 'CAP, 100PF, +/-5%, 630V, C0G, 1206'                                              | 'NFND'    
 'CL1003321A'     | '1000PF'  | '+/-5%'      = 'SMC_1206R'                | '(SMC_1206R)'                                   | 'CAP, 1000PF, +/-5%, 630V, C0G, 1206'                                             | 'NFND'    
 'CL1003322A'     | '150PF'   | '+/-5%'      = 'SMC_1206R'                | '(SMC_1206R)'                                   | 'CAP, 150PF, +/-5%, 630V, C0G, 1206'                                              | 'NFND'    
 'CL1003323A'     | '1500PF'  | '+/-5%'      = 'SMC_1206R'                | '(SMC_1206R)'                                   | 'CAP, 1500PF, +/-5%, 630V, C0G, 1206'                                             | 'NFND'    
 'CL1003324A'     | '220PF'   | '+/-5%'      = 'SMC_1206R'                | '(SMC_1206R)'                                   | 'CAP, 220PF, +/-5%, 630V, C0G, 1206'                                              | 'NFND'    
 'CL1003325A'     | '2200PF'  | '+/-5%'      = 'SMC_1206R'                | '(SMC_1206R)'                                   | 'CAP, 2200PF, +/-5%, 630V, C0G, 1206'                                             | 'NFND'    
 'CL1003326A'     | '2700PF'  | '+/-5%'      = 'SMC_1206R'                | '(SMC_1206R)'                                   | 'CAP, 2700PF, +/-5%, 630V, C0G, 1206'                                             | 'NFND'    
 'CL1003327A'     | '330PF'   | '+/-5%'      = 'SMC_1206R'                | '(SMC_1206R)'                                   | 'CAP, 330PF, +/-5%, 630V, C0G, 1206'                                              | 'NFND'    
 'CL1003328A'     | '3300PF'  | '+/-5%'      = 'SMC_1206R'                | '(SMC_1206R)'                                   | 'CAP, 3300PF, +/-5%, 630V, C0G, 1206'                                             | 'NFND'    
 'CL1003329A'     | '470PF'   | '+/-5%'      = 'SMC_1206R'                | '(SMC_1206R)'                                   | 'CAP, 470PF, +/-5%, 630V, C0G, 1206'                                              | 'NFND'    
 'CL1003330A'     | '680PF'   | '+/-5%'      = 'SMC_1206R'                | '(SMC_1206R)'                                   | 'CAP, 680PF, +/-5%, 630V, C0G, 1206'                                              | 'NFND'    
 'CL1003331A'     | '10UF'    | '+/-20%'     = 'SMC_1206R'                | '(SMC_1206R)'                                   | 'CAP, 10UF, +/-20%, 6.3V, X5R, 1206'                                              | 'NFND'    
 'CL1003332A'     | '22UF'    | '+/-20%'     = 'SMC_1206R'                | '(SMC_1206R)'                                   | 'CAP, 22UF, +/-20%, 6.3V, X5R, 1206'                                              | 'NFND'    
 'CL1003333A'     | '33UF'    | '+/-20%'     = 'SMC_1206R'                | '(SMC_1206R)'                                   | 'CAP, 33UF, +/-20%, 6.3V, X5R, 1206'                                              | 'NFND'    
 'G108-0C336-BM'  | '33UF'    | '+/-20%'     = 'SMC_1206R'                | '(SMC_1206R)'                                   | 'CAP, 33UF, +/-20%, 6.3V, X5R, 1206'                                              | 'NFND'    
 'CL1003334A'     | '47UF'    | '+/-20%'     = 'SMC_1206R'                | '(SMC_1206R)'                                   | 'CAP, 47UF, +/-20%, 6.3V, X5R, 1206'                                              | 'NFND'    
 'G101-00011-01'  | '47UF'    | '+/-20%'     = 'SMC_1206R_H071'           | '(SMC_1206R_H071)'                              | 'CAP, 47UF, +/-20%, 6.3V, X5R, 1206'                                              | 'NFND'    
 'CL1003335A'     | '10UF'    | '+/-20%'     = 'SMC_1206R'                | '(SMC_1206R)'                                   | 'CAP, 10UF, +/-20%, 16V, X5R, 1206'                                               | 'NFND'    
 'CL1003336A'     | '2.2UF'   | '+/-10%'     = 'SMC_1206R'                | '(SMC_1206R)'                                   | 'CAP, 2.2UF, +/-10%, 16V, X5R, 1206'                                              | 'NFND'    
 'CL1003337A'     | '3.3UF'   | '+/-10%'     = 'SMC_1206R'                | '(SMC_1206R)'                                   | 'CAP, 3.3UF, +/-10%, 16V, X5R, 1206'                                              | 'NFND'    
 'CL1003338A'     | '4.7UF'   | '+/-10%'     = 'SMC_1206R'                | '(SMC_1206R)'                                   | 'CAP, 4.7UF, +/-10%, 16V, X5R, 1206'                                              | 'NFND'    
 'CL1003339A'     | '1UF'     | '+/-10%'     = 'SMC_1206R'                | '(SMC_1206R)'                                   | 'CAP, 1UF, +/-10%, 25V, X5R, 1206'                                                | 'NFND'    
 'CL1003340A'     | '10UF'    | '+/-20%'     = 'SMC_1206R'                | '(SMC_1206R)'                                   | 'CAP, 10UF, +/-20%, 25V, X5R, 1206'                                               | 'NFND'    
 'CL1003341A'     | '2.2UF'   | '+/-10%'     = 'SMC_1206R'                | '(SMC_1206R)'                                   | 'CAP, 2.2UF, +/-10%, 25V, X5R, 1206'                                              | 'NFND'    
 'CL1003342A'     | '4.7UF'   | '+/-10%'     = 'SMC_1206R'                | '(SMC_1206R)'                                   | 'CAP, 4.7UF, +/-10%, 25V, X5R, 1206'                                              | 'NFND'    
 'CL1003343A'     | '1UF'     | '+/-10%'     = 'SMC_1206R'                | '(SMC_1206R)'                                   | 'CAP, 1UF, +/-10%, 50V, X5R, 1206'                                                | 'NFND'    
 'CL1003344A'     | '470NF'   | '+/-10%'     = 'SMC_1206R'                | '(SMC_1206R)'                                   | 'CAP, 470NF, +/-10%, 50V, X5R, 1206'                                              | 'NFND'    
 'CL1003345A'     | '1UF'     | '+/-10%'     = 'SMC_1206R'                | '(SMC_1206R)'                                   | 'CAP, 1UF, +/-10%, 16V, X7R, 1206'                                                | 'NFND'    
 'CL1003346A'     | '10UF'    | '+/-20%'     = 'SMC_1206R'                | '(SMC_1206R)'                                   | 'CAP, 10UF, +/-20%, 16V, X7R, 1206'                                               | 'NFND'    
 'CL1003347A'     | '2.2UF'   | '+/-10%'     = 'SMC_1206R'                | '(SMC_1206R)'                                   | 'CAP, 2.2UF, +/-10%, 16V, X7R, 1206'                                              | 'NFND'    
 'CL1003348A'     | '4.7UF'   | '+/-10%'     = 'SMC_1206R'                | '(SMC_1206R)'                                   | 'CAP, 4.7UF, +/-10%, 16V, X7R, 1206'                                              | 'NFND'    
 'CL1003349A'     | '1UF'     | '+/-10%'     = 'SMC_1206R'                | '(SMC_1206R)'                                   | 'CAP, 1UF, +/-10%, 25V, X7R, 1206'                                                | 'NFND'    
 'CL1003350A'     | '1.5UF'   | '+/-10%'     = 'SMC_1206R'                | '(SMC_1206R)'                                   | 'CAP, 1.5UF, +/-10%, 25V, X7R, 1206'                                              | 'NFND'    
 'CL1003351A'     | '2.2UF'   | '+/-10%'     = 'SMC_1206R'                | '(SMC_1206R)'                                   | 'CAP, 2.2UF, +/-10%, 25V, X7R, 1206'                                              | 'NFND'    
 'CL1003352A'     | '3.3UF'   | '+/-10%'     = 'SMC_1206R'                | '(SMC_1206R)'                                   | 'CAP, 3.3UF, +/-10%, 25V, X7R, 1206'                                              | 'NFND'    
 'CL1003353A'     | '4.7UF'   | '+/-10%'     = 'SMC_1206R'                | '(SMC_1206R)'                                   | 'CAP, 4.7UF, +/-10%, 25V, X7R, 1206'                                              | 'NFND'    
 'CL1003354A'     | '1UF'     | '+/-10%'     = 'SMC_1206R'                | '(SMC_1206R)'                                   | 'CAP, 1UF, +/-10%, 50V, X7R, 1206'                                                | 'NFND'    
 'CL1003355A'     | '470NF'   | '+/-10%'     = 'SMC_1206R'                | '(SMC_1206R)'                                   | 'CAP, 470NF, +/-10%, 50V, X7R, 1206'                                              | 'NFND'    
 'CL1003356A'     | '680NF'   | '+/-10%'     = 'SMC_1206R'                | '(SMC_1206R)'                                   | 'CAP, 680NF, +/-10%, 50V, X7R, 1206'                                              | 'NFND'    
 'CL1003357A'     | '1UF'     | '+/-10%'     = 'SMC_1206R'                | '(SMC_1206R)'                                   | 'CAP, 1UF, +/-10%, 100V, X7R, 1206'                                               | 'NFND'    
 'CL1003358A'     | '150NF'   | '+/-10%'     = 'SMC_1206R'                | '(SMC_1206R)'                                   | 'CAP, 150NF, +/-10%, 100V, X7R, 1206'                                             | 'NFND'    
 'CL1003359A'     | '220NF'   | '+/-10%'     = 'SMC_1206R'                | '(SMC_1206R)'                                   | 'CAP, 220NF, +/-10%, 100V, X7R, 1206'                                             | 'NFND'    
 'CL1003360A'     | '33NF'    | '+/-10%'     = 'SMC_1206R'                | '(SMC_1206R)'                                   | 'CAP, 33NF, +/-10%, 100V, X7R, 1206'                                              | 'NFND'    
 'CL1003361A'     | '330NF'   | '+/-10%'     = 'SMC_1206R'                | '(SMC_1206R)'                                   | 'CAP, 330NF, +/-10%, 100V, X7R, 1206'                                             | 'NFND'    
 'CL1003362A'     | '47NF'    | '+/-10%'     = 'SMC_1206R'                | '(SMC_1206R)'                                   | 'CAP, 47NF, +/-10%, 100V, X7R, 1206'                                              | 'NFND'    
 'CL1003363A'     | '470NF'   | '+/-10%'     = 'SMC_1206R'                | '(SMC_1206R)'                                   | 'CAP, 470NF, +/-10%, 100V, X7R, 1206'                                             | 'NFND'    
 'CL1003364A'     | '68NF'    | '+/-10%'     = 'SMC_1206R'                | '(SMC_1206R)'                                   | 'CAP, 68NF, +/-10%, 100V, X7R, 1206'                                              | 'NFND'    
 'CL1003365A'     | '680NF'   | '+/-10%'     = 'SMC_1206R'                | '(SMC_1206R)'                                   | 'CAP, 680NF, +/-10%, 100V, X7R, 1206'                                             | 'NFND'    
 'CL1003366A'     | '100NF'   | '+/-10%'     = 'SMC_1206R'                | '(SMC_1206R)'                                   | 'CAP, 100NF, +/-10%, 250V, X7R, 1206'                                             | 'NFND'    
 'CL1003367A'     | '22NF'    | '+/-10%'     = 'SMC_1206R'                | '(SMC_1206R)'                                   | 'CAP, 22NF, +/-10%, 250V, X7R, 1206'                                              | 'NFND'    
 'CL1003368A'     | '33NF'    | '+/-10%'     = 'SMC_1206R'                | '(SMC_1206R)'                                   | 'CAP, 33NF, +/-10%, 250V, X7R, 1206'                                              | 'NFND'    
 'CL1003369A'     | '47NF'    | '+/-10%'     = 'SMC_1206R'                | '(SMC_1206R)'                                   | 'CAP, 47NF, +/-10%, 250V, X7R, 1206'                                              | 'NFND'    
 'CL1003370A'     | '68NF'    | '+/-10%'     = 'SMC_1206R'                | '(SMC_1206R)'                                   | 'CAP, 68NF, +/-10%, 250V, X7R, 1206'                                              | 'NFND'    
 'CL1003371A'     | '1000PF'  | '+/-10%'     = 'SMC_1206R'                | '(SMC_1206R)'                                   | 'CAP, 1000PF, +/-10%, 630V, X7R, 1206'                                            | 'NFND'    
 'CL1003372A'     | '10NF'    | '+/-10%'     = 'SMC_1206R'                | '(SMC_1206R)'                                   | 'CAP, 10NF, +/-10%, 630V, X7R, 1206'                                              | 'NFND'    
 'CL1003373A'     | '1500PF'  | '+/-10%'     = 'SMC_1206R'                | '(SMC_1206R)'                                   | 'CAP, 1500PF, +/-10%, 630V, X7R, 1206'                                            | 'NFND'    
 'CL1003374A'     | '15NF'    | '+/-10%'     = 'SMC_1206R'                | '(SMC_1206R)'                                   | 'CAP, 15NF, +/-10%, 630V, X7R, 1206'                                              | 'NFND'    
 'CL1003375A'     | '2200PF'  | '+/-10%'     = 'SMC_1206R'                | '(SMC_1206R)'                                   | 'CAP, 2200PF, +/-10%, 630V, X7R, 1206'                                            | 'NFND'    
 'CL1003376A'     | '22NF'    | '+/-10%'     = 'SMC_1206R'                | '(SMC_1206R)'                                   | 'CAP, 22NF, +/-10%, 630V, X7R, 1206'                                              | 'NFND'    
 'CL1003377A'     | '3300PF'  | '+/-10%'     = 'SMC_1206R'                | '(SMC_1206R)'                                   | 'CAP, 3300PF, +/-10%, 630V, X7R, 1206'                                            | 'NFND'    
 'CL1003378A'     | '33NF'    | '+/-10%'     = 'SMC_1206R'                | '(SMC_1206R)'                                   | 'CAP, 33NF, +/-10%, 630V, X7R, 1206'                                              | 'NFND'    
 'CL1003379A'     | '4700PF'  | '+/-10%'     = 'SMC_1206R'                | '(SMC_1206R)'                                   | 'CAP, 4700PF, +/-10%, 630V, X7R, 1206'                                            | 'NFND'    
 'CL1003380A'     | '6800PF'  | '+/-10%'     = 'SMC_1206R'                | '(SMC_1206R)'                                   | 'CAP, 6800PF, +/-10%, 630V, X7R, 1206'                                            | 'NFND'    
 'CL1003381A'     | '47UF'    | '-20/+80%'    = 'SMC_1206R'                | '(SMC_1206R)'                                   | 'CAP, 47UF, -20/+80%, 6.3V, Y5V, 1206'                                            | 'NFND'    
 'CL1003382A'     | '10UF'    | '-20/+80%'    = 'SMC_1206R'                | '(SMC_1206R)'                                   | 'CAP, 10UF, -20/+80%, 10V, Y5V, 1206'                                             | 'NFND'    
 'CL1003383A'     | '22UF'    | '-20/+80%'    = 'SMC_1206R'                | '(SMC_1206R)'                                   | 'CAP, 22UF, -20/+80%, 10V, Y5V, 1206'                                             | 'NFND'    
 'CL1003384A'     | '10UF'    | '-20/+80%'    = 'SMC_1206R'                | '(SMC_1206R)'                                   | 'CAP, 10UF, -20/+80%, 16V, Y5V, 1206'                                             | 'NFND'    
 'CL1003385A'     | '22UF'    | '-20/+80%'    = 'SMC_1206R'                | '(SMC_1206R)'                                   | 'CAP, 22UF, -20/+80%, 16V, Y5V, 1206'                                             | 'NFND'    
 'CL1003386A'     | '10UF'    | '-20/+80%'    = 'SMC_1206R'                | '(SMC_1206R)'                                   | 'CAP, 10UF, -20/+80%, 25V, Y5V, 1206'                                             | 'NFND'    
 'CL1003387A'     | '4.7UF'   | '-20/+80%'    = 'SMC_1206R'                | '(SMC_1206R)'                                   | 'CAP, 4.7UF, -20/+80%, 50V, Y5V, 1206'                                            | 'NFND'    
 'CL1003388A'     | '47NF'    | '+/-5%'      = 'SMC_1210R'                | '(SMC_1210R)'                                   | 'CAP, 47NF, +/-5%, 100V, C0G, 1210'                                               | 'NFND'    
 'CL1003389A'     | '10NF'    | '+/-5%'      = 'SMC_1210R'                | '(SMC_1210R)'                                   | 'CAP, 10NF, +/-5%, 250V, C0G, 1210'                                               | 'NFND'    
 'CL1003390A'     | '6800PF'  | '+/-5%'      = 'SMC_1210R'                | '(SMC_1210R)'                                   | 'CAP, 6800PF, +/-5%, 630V, C0G, 1210'                                             | 'NFND'    
 'CL1003391A'     | '10UF'    | '+/-20%'     = 'SMC_1210R'                | '(SMC_1210R)'                                   | 'CAP, 10UF, +/-20%, 10V, X5R, 1210'                                               | 'NFND'    
 'CL1003392A'     | '22UF'    | '+/-20%'     = 'SMC_1210R'                | '(SMC_1210R)'                                   | 'CAP, 22UF, +/-20%, 10V, X5R, 1210'                                               | 'NFND'    
 'CL1003393A'     | '10UF'    | '+/-20%'     = 'SMC_1210R'                | '(SMC_1210R)'                                   | 'CAP, 10UF, +/-20%, 16V, X5R, 1210'                                               | 'NFND'    
 'CL1003394A'     | '10UF'    | '+/-20%'     = 'SMC_1210R'                | '(SMC_1210R)'                                   | 'CAP, 10UF, +/-20%, 25V, X5R, 1210'                                               | 'NFND'    
 'CL1003395A'     | '4.7UF'   | '+/-10%'     = 'SMC_1210R'                | '(SMC_1210R)'                                   | 'CAP, 4.7UF, +/-10%, 25V, X5R, 1210'                                              | 'NFND'    
 'CL1003396A'     | '2.2UF'   | '+/-10%'     = 'SMC_1210R'                | '(SMC_1210R)'                                   | 'CAP, 2.2UF, +/-10%, 50V, X5R, 1210'                                              | 'NFND'    
 'CL1003397A'     | '3.3UF'   | '+/-10%'     = 'SMC_1210R'                | '(SMC_1210R)'                                   | 'CAP, 3.3UF, +/-10%, 50V, X5R, 1210'                                              | 'NFND'    
 'CL1003398A'     | '10UF'    | '+/-20%'     = 'SMC_1210R'                | '(SMC_1210R)'                                   | 'CAP, 10UF, +/-20%, 16V, X7R, 1210'                                               | 'NFND'    
 'CL1003399A'     | '15UF'    | '+/-20%'     = 'SMC_1210R'                | '(SMC_1210R)'                                   | 'CAP, 15UF, +/-20%, 16V, X7R, 1210'                                               | 'NFND'    
 'CL1003400A'     | '22UF'    | '+/-20%'     = 'SMC_1210R'                | '(SMC_1210R)'                                   | 'CAP, 22UF, +/-20%, 16V, X7R, 1210'                                               | 'NFND'    
 'CL1003401A'     | '10UF'    | '+/-20%'     = 'SMC_1210R'                | '(SMC_1210R)'                                   | 'CAP, 10UF, +/-20%, 25V, X7R, 1210'                                               | 'NFND'    
 'CL1003402A'     | '2.2UF'   | '+/-10%'     = 'SMC_1210R'                | '(SMC_1210R)'                                   | 'CAP, 2.2UF, +/-10%, 25V, X7R, 1210'                                              | 'NFND'    
 'CL1003403A'     | '3.3UF'   | '+/-10%'     = 'SMC_1210R'                | '(SMC_1210R)'                                   | 'CAP, 3.3UF, +/-10%, 25V, X7R, 1210'                                              | 'NFND'    
 'CL1003404A'     | '4.7UF'   | '+/-10%'     = 'SMC_1210R'                | '(SMC_1210R)'                                   | 'CAP, 4.7UF, +/-10%, 25V, X7R, 1210'                                              | 'NFND'    
 'CL1003405A'     | '1UF'     | '+/-10%'     = 'SMC_1210R'                | '(SMC_1210R)'                                   | 'CAP, 1UF, +/-10%, 50V, X7R, 1210'                                                | 'NFND'    
 'CL1003406A'     | '1.5UF'   | '+/-10%'     = 'SMC_1210R'                | '(SMC_1210R)'                                   | 'CAP, 1.5UF, +/-10%, 50V, X7R, 1210'                                              | 'NFND'    
 'CL1003407A'     | '2.2UF'   | '+/-10%'     = 'SMC_1210R'                | '(SMC_1210R)'                                   | 'CAP, 2.2UF, +/-10%, 50V, X7R, 1210'                                              | 'NFND'    
 'CL1003408A'     | '3.3UF'   | '+/-10%'     = 'SMC_1210R'                | '(SMC_1210R)'                                   | 'CAP, 3.3UF, +/-10%, 50V, X7R, 1210'                                              | 'NFND'    
 'CL1003409A'     | '4.7UF'   | '+/-10%'     = 'SMC_1210R'                | '(SMC_1210R)'                                   | 'CAP, 4.7UF, +/-10%, 50V, X7R, 1210'                                              | 'NFND'    
 'CL1003410A'     | '1UF'     | '+/-10%'     = 'SMC_1210R'                | '(SMC_1210R)'                                   | 'CAP, 1UF, +/-10%, 100V, X7R, 1210'                                               | 'NFND'    
 'CL1003411A'     | '2.2UF'   | '+/-10%'     = 'SMC_1210R'                | '(SMC_1210R)'                                   | 'CAP, 2.2UF, +/-10%, 100V, X7R, 1210'                                             | 'NFND'    
 'CL1003412A'     | '330NF'   | '+/-10%'     = 'SMC_1210R'                | '(SMC_1210R)'                                   | 'CAP, 330NF, +/-10%, 100V, X7R, 1210'                                             | 'NFND'    
 'CL1003413A'     | '470NF'   | '+/-10%'     = 'SMC_1210R'                | '(SMC_1210R)'                                   | 'CAP, 470NF, +/-10%, 100V, X7R, 1210'                                             | 'NFND'    
 'CL1003414A'     | '680NF'   | '+/-10%'     = 'SMC_1210R'                | '(SMC_1210R)'                                   | 'CAP, 680NF, +/-10%, 100V, X7R, 1210'                                             | 'NFND'    
 'CL1003415A'     | '100NF'   | '+/-10%'     = 'SMC_1210R'                | '(SMC_1210R)'                                   | 'CAP, 100NF, +/-10%, 250V, X7R, 1210'                                             | 'NFND'    
 'CL1003416A'     | '150NF'   | '+/-10%'     = 'SMC_1210R'                | '(SMC_1210R)'                                   | 'CAP, 150NF, +/-10%, 250V, X7R, 1210'                                             | 'NFND'    
 'CL1003417A'     | '220NF'   | '+/-10%'     = 'SMC_1210R'                | '(SMC_1210R)'                                   | 'CAP, 220NF, +/-10%, 250V, X7R, 1210'                                             | 'NFND'    
 'CL1003418A'     | '47NF'    | '+/-10%'     = 'SMC_1210R'                | '(SMC_1210R)'                                   | 'CAP, 47NF, +/-10%, 630V, X7R, 1210'                                              | 'NFND'    
 'CL1003419A'     | '68NF'    | '+/-10%'     = 'SMC_1210R'                | '(SMC_1210R)'                                   | 'CAP, 68NF, +/-10%, 630V, X7R, 1210'                                              | 'NFND'    
 'CL1003420A'     | '100UF'   | '-20/+80%'    = 'SMC_1210R'                | '(SMC_1210R)'                                   | 'CAP, 100UF, -20/+80%, 6.3V, Y5V, 1210'                                           | 'NFND'    
 'CL1003421A'     | '47UF'    | '-20/+80%'    = 'SMC_1210R'                | '(SMC_1210R)'                                   | 'CAP, 47UF, -20/+80%, 6.3V, Y5V, 1210'                                            | 'NFND'    
 'CL1003422A'     | '10UF'    | '-20/+80%'    = 'SMC_1210R'                | '(SMC_1210R)'                                   | 'CAP, 10UF, -20/+80%, 10V, Y5V, 1210'                                             | 'NFND'    
 'CL1003423A'     | '10UF'    | '-20/+80%'    = 'SMC_1210R'                | '(SMC_1210R)'                                   | 'CAP, 10UF, -20/+80%, 16V, Y5V, 1210'                                             | 'NFND'    
 'CL1003424A'     | '22UF'    | '-20/+80%'    = 'SMC_1210R'                | '(SMC_1210R)'                                   | 'CAP, 22UF, -20/+80%, 16V, Y5V, 1210'                                             | 'NFND'    
 'CL1003425A'     | '10UF'    | '-20/+80%'    = 'SMC_1210R'                | '(SMC_1210R)'                                   | 'CAP, 10UF, -20/+80%, 25V, Y5V, 1210'                                             | 'NFND'    
 'CL1003426A'     | '22UF'    | '-20/+80%'    = 'SMC_1210R'                | '(SMC_1210R)'                                   | 'CAP, 22UF, -20/+80%, 25V, Y5V, 1210'                                             | 'NFND'    
 'CL1003427A'     | '10UF'    | '-20/+80%'    = 'SMC_1210R'                | '(SMC_1210R)'                                   | 'CAP, 10UF, -20/+80%, 50V, Y5V, 1210'                                             | 'NFND'    
 'CL1003428A'     | '4.7UF'   | '-20/+80%'    = 'SMC_1210R'                | '(SMC_1210R)'                                   | 'CAP, 4.7UF, -20/+80%, 50V, Y5V, 1210'                                            | 'NFND'    
 'CL1003429A'     | '100PF'   | '+/-10%'     = 'SMC_1808'                 | '(SMC_1808)'                                    | 'CAP, 100PF, +/-10%, 3000V, C0G, 1808'                                            | 'NFND'    
 'CL1003430A'     | '12PF'    | '+/-5%'      = 'SMC_1808'                 | '(SMC_1808)'                                    | 'CAP, 12PF, +/-5%, 3000V, C0G, 1808'                                              | 'NFND'    
 'CL1003431A'     | '15PF'    | '+/-10%'     = 'SMC_1808'                 | '(SMC_1808)'                                    | 'CAP, 15PF, +/-10%, 3000V, C0G, 1808'                                             | 'NFND'    
 'CL1003432A'     | '33PF'    | '+/-5%'      = 'SMC_1808'                 | '(SMC_1808)'                                    | 'CAP, 33PF, +/-5%, 3000V, C0G, 1808'                                              | 'NFND'    
 'CL1003433A'     | '47PF'    | '+/-10%'     = 'SMC_1808'                 | '(SMC_1808)'                                    | 'CAP, 47PF, +/-10%, 3000V, C0G, 1808'                                             | 'NFND'    
 'CL1003434A'     | '1000PF'  | '+/-10%'     = 'SMC_1808'                 | '(SMC_1808)'                                    | 'CAP, 1000PF, +/-10%, 1000V, X7R, 1808'                                           | 'NFND'    
 'CL1003435A'     | '1000PF'  | '+/-10%'     = 'SMC_1808'                 | '(SMC_1808)'                                    | 'CAP, 1000PF, +/-10%, 2000V, X7R, 1808'                                           | 'NFND'    
 'CL1003436A'     | '470PF'   | '+/-10%'     = 'SMC_1808'                 | '(SMC_1808)'                                    | 'CAP, 470PF, +/-10%, 2000V, X7R, 1808'                                            | 'NFND'    
 'CL1003437A'     | '100NF'   | '+/-5%'      = 'SMC_1812R'                | '(SMC_1812R)'                                   | 'CAP, 100NF, +/-5%, 100V, C0G, 1812'                                              | 'NFND'    
 'CL1003438A'     | '47NF'    | '+/-5%'      = 'SMC_1812R'                | '(SMC_1812R)'                                   | 'CAP, 47NF, +/-5%, 100V, C0G, 1812'                                               | 'NFND'    
 'CL1003439A'     | '22NF'    | '+/-5%'      = 'SMC_1812R'                | '(SMC_1812R)'                                   | 'CAP, 22NF, +/-5%, 250V, C0G, 1812'                                               | 'NFND'    
 'CL1003440A'     | '47NF'    | '+/-5%'      = 'SMC_1812R'                | '(SMC_1812R)'                                   | 'CAP, 47NF, +/-5%, 250V, C0G, 1812'                                               | 'NFND'    
 'CL1003441A'     | '10NF'    | '+/-5%'      = 'SMC_1812R'                | '(SMC_1812R)'                                   | 'CAP, 10NF, +/-5%, 630V, C0G, 1812'                                               | 'NFND'    
 'CL1003442A'     | '22NF'    | '+/-5%'      = 'SMC_1812R'                | '(SMC_1812R)'                                   | 'CAP, 22NF, +/-5%, 630V, C0G, 1812'                                               | 'NFND'    
 'CL1003443A'     | '100UF'   | '+/-20%'     = 'SMC_1812R'                | '(SMC_1812R)'                                   | 'CAP, 100UF, +/-20%, 6.3V, X5R, 1812'                                             | 'NFND'    
 'CL1003444A'     | '47UF'    | '+/-20%'     = 'SMC_1812R'                | '(SMC_1812R)'                                   | 'CAP, 47UF, +/-20%, 6.3V, X5R, 1812'                                              | 'NFND'    
 'CL1003445A'     | '22UF'    | '+/-20%'     = 'SMC_1812R'                | '(SMC_1812R)'                                   | 'CAP, 22UF, +/-20%, 10V, X5R, 1812'                                               | 'NFND'    
 'CL1003446A'     | '47UF'    | '+/-20%'     = 'SMC_1812R'                | '(SMC_1812R)'                                   | 'CAP, 47UF, +/-20%, 10V, X5R, 1812'                                               | 'NFND'    
 'CL1003447A'     | '22UF'    | '+/-20%'     = 'SMC_1812R'                | '(SMC_1812R)'                                   | 'CAP, 22UF, +/-20%, 16V, X5R, 1812'                                               | 'NFND'    
 'CL1003448A'     | '33UF'    | '+/-20%'     = 'SMC_1812R'                | '(SMC_1812R)'                                   | 'CAP, 33UF, +/-20%, 16V, X5R, 1812'                                               | 'NFND'    
 'CL1003449A'     | '10UF'    | '+/-20%'     = 'SMC_1812R'                | '(SMC_1812R)'                                   | 'CAP, 10UF, +/-20%, 25V, X5R, 1812'                                               | 'NFND'    
 'CL1003450A'     | '4.7UF'   | '+/-10%'     = 'SMC_1812R'                | '(SMC_1812R)'                                   | 'CAP, 4.7UF, +/-10%, 50V, X5R, 1812'                                              | 'NFND'    
 'CL1003451A'     | '10UF'    | '+/-20%'     = 'SMC_1812R'                | '(SMC_1812R)'                                   | 'CAP, 10UF, +/-20%, 16V, X7R, 1812'                                               | 'NFND'    
 'CL1003452A'     | '22UF'    | '+/-20%'     = 'SMC_1812R'                | '(SMC_1812R)'                                   | 'CAP, 22UF, +/-20%, 16V, X7R, 1812'                                               | 'NFND'    
 'CL1003453A'     | '33UF'    | '+/-20%'     = 'SMC_1812R'                | '(SMC_1812R)'                                   | 'CAP, 33UF, +/-20%, 16V, X7R, 1812'                                               | 'NFND'    
 'CL1003454A'     | '10UF'    | '+/-20%'     = 'SMC_1812R'                | '(SMC_1812R)'                                   | 'CAP, 10UF, +/-20%, 25V, X7R, 1812'                                               | 'NFND'    
 'CL1003455A'     | '15UF'    | '+/-20%'     = 'SMC_1812R'                | '(SMC_1812R)'                                   | 'CAP, 15UF, +/-20%, 25V, X7R, 1812'                                               | 'NFND'    
 'CL1003456A'     | '22UF'    | '+/-20%'     = 'SMC_1812R'                | '(SMC_1812R)'                                   | 'CAP, 22UF, +/-20%, 25V, X7R, 1812'                                               | 'NFND'    
 'CL1003457A'     | '4.7UF'   | '+/-10%'     = 'SMC_1812R'                | '(SMC_1812R)'                                   | 'CAP, 4.7UF, +/-10%, 25V, X7R, 1812'                                              | 'NFND'    
 'CL1003458A'     | '1UF'     | '+/-10%'     = 'SMC_1812R'                | '(SMC_1812R)'                                   | 'CAP, 1UF, +/-10%, 50V, X7R, 1812'                                                | 'NFND'    
 'CL1003459A'     | '2.2UF'   | '+/-10%'     = 'SMC_1812R'                | '(SMC_1812R)'                                   | 'CAP, 2.2UF, +/-10%, 50V, X7R, 1812'                                              | 'NFND'    
 'CL1003460A'     | '3.3UF'   | '+/-10%'     = 'SMC_1812R'                | '(SMC_1812R)'                                   | 'CAP, 3.3UF, +/-10%, 50V, X7R, 1812'                                              | 'NFND'    
 'CL1003461A'     | '4.7UF'   | '+/-10%'     = 'SMC_1812R'                | '(SMC_1812R)'                                   | 'CAP, 4.7UF, +/-10%, 50V, X7R, 1812'                                              | 'NFND'    
 'CL1003462A'     | '6.8UF'   | '+/-10%'     = 'SMC_1812R'                | '(SMC_1812R)'                                   | 'CAP, 6.8UF, +/-10%, 50V, X7R, 1812'                                              | 'NFND'    
 'CL1003463A'     | '1UF'     | '+/-10%'     = 'SMC_1812R'                | '(SMC_1812R)'                                   | 'CAP, 1UF, +/-10%, 100V, X7R, 1812'                                               | 'NFND'    
 'CL1003464A'     | '1UF'     | '+/-20%'     = 'SMC_1812R'                | '(SMC_1812R)'                                   | 'CAP, 1UF, +/-20%, 100V, X7R, 1812'                                               | 'NFND'    
 'CL1003465A'     | '1.5UF'   | '+/-10%'     = 'SMC_1812R'                | '(SMC_1812R)'                                   | 'CAP, 1.5UF, +/-10%, 100V, X7R, 1812'                                             | 'NFND'    
 'CL1003466A'     | '2.2UF'   | '+/-10%'     = 'SMC_1812R'                | '(SMC_1812R)'                                   | 'CAP, 2.2UF, +/-10%, 100V, X7R, 1812'                                             | 'NFND'    
 'CL1003467A'     | '2.2UF'   | '+/-20%'     = 'SMC_1812R'                | '(SMC_1812R)'                                   | 'CAP, 2.2UF, +/-20%, 100V, X7R, 1812'                                             | 'NFND'    
 'CL1003468A'     | '470NF'   | '+/-10%'     = 'SMC_1812R'                | '(SMC_1812R)'                                   | 'CAP, 470NF, +/-10%, 100V, X7R, 1812'                                             | 'NFND'    
 'CL1003469A'     | '680NF'   | '+/-10%'     = 'SMC_1812R'                | '(SMC_1812R)'                                   | 'CAP, 680NF, +/-10%, 100V, X7R, 1812'                                             | 'NFND'    
 'CL1003470A'     | '220NF'   | '+/-10%'     = 'SMC_1812R'                | '(SMC_1812R)'                                   | 'CAP, 220NF, +/-10%, 250V, X7R, 1812'                                             | 'NFND'    
 'CL1003471A'     | '330NF'   | '+/-10%'     = 'SMC_1812R'                | '(SMC_1812R)'                                   | 'CAP, 330NF, +/-10%, 250V, X7R, 1812'                                             | 'NFND'    
 'CL1003472A'     | '470NF'   | '+/-10%'     = 'SMC_1812R'                | '(SMC_1812R)'                                   | 'CAP, 470NF, +/-10%, 250V, X7R, 1812'                                             | 'NFND'    
 'CL1003473A'     | '100NF'   | '+/-10%'     = 'SMC_1812R'                | '(SMC_1812R)'                                   | 'CAP, 100NF, +/-10%, 630V, X7R, 1812'                                             | 'NFND'    
 'CL1003474A'     | '4700PF'  | '+/-10%'     = 'SMC_1812R'                | '(SMC_1812R)'                                   | 'CAP, 4700PF, +/-10%, 1000V, X7R, 1812'                                           | 'NFND'    
 'CL1003475A'     | '2200PF'  | '+/-10%'     = 'SMC_1812R'                | '(SMC_1812R)'                                   | 'CAP, 2200PF, +/-10%, 2000V, X7R, 1812'                                           | 'NFND'    
 'CL1003476A'     | '100UF'   | '-20/+80%'    = 'SMC_1812R'                | '(SMC_1812R)'                                   | 'CAP, 100UF, -20/+80%, 10V, Y5V, 1812'                                            | 'NFND'    
 'CL1003477A'     | '47UF'    | '-20/+80%'    = 'SMC_1812R'                | '(SMC_1812R)'                                   | 'CAP, 47UF, -20/+80%, 10V, Y5V, 1812'                                             | 'NFND'    
 'CL1003478A'     | '22UF'    | '-20/+80%'    = 'SMC_1812R'                | '(SMC_1812R)'                                   | 'CAP, 22UF, -20/+80%, 25V, Y5V, 1812'                                             | 'NFND'    
 'CL1003479A'     | '10UF'    | '-20/+80%'    = 'SMC_1812R'                | '(SMC_1812R)'                                   | 'CAP, 10UF, -20/+80%, 50V, Y5V, 1812'                                             | 'NFND'    
 'CL1003480A'     | '100UF'   | '+/-20%'     = ''                         | ''                                              | 'CAP, 100UF, +/-20%, 6.3V, X5R, 2220'                                             | 'NFND'    
 'CL1003481A'     | '68UF'    | '+/-20%'     = 'SMC_C_224X196'            | '(SMC_C_224X196)'                               | 'CAP, 68UF, +/-20%, 10V, X5R, 2220'                                               | 'NFND'    
 'CL1003482A'     | '33UF'    | '+/-20%'     = 'SMC_C_224X196'            | '(SMC_C_224X196)'                               | 'CAP, 33UF, +/-20%, 16V, X5R, 2220'                                               | 'NFND'    
 'CL1003483A'     | '22UF'    | '+/-20%'     = 'SMC_C_224X196'            | '(SMC_C_224X196)'                               | 'CAP, 22UF, +/-20%, 25V, X5R, 2220'                                               | 'NFND'    
 'CL1003484A'     | '10UF'    | '+/-20%'     = 'SMC_C_224X196'            | '(SMC_C_224X196)'                               | 'CAP, 10UF, +/-20%, 50V, X5R, 2220'                                               | 'NFND'    
 'CL1003485A'     | '22UF'    | '+/-20%'     = 'SMC_C_224X196'            | '(SMC_C_224X196)'                               | 'CAP, 22UF, +/-20%, 16V, X7R, 2220'                                               | 'NFND'    
 'CL1003486A'     | '47UF'    | '+/-20%'     = 'SMC_C_224X196'            | '(SMC_C_224X196)'                               | 'CAP, 47UF, +/-20%, 16V, X7R, 2220'                                               | 'NFND'    
 'CL1003487A'     | '10UF'    | '+/-20%'     = 'SMC_C_224X196'            | '(SMC_C_224X196)'                               | 'CAP, 10UF, +/-20%, 25V, X7R, 2220'                                               | 'NFND'    
 'CL1003488A'     | '22UF'    | '+/-20%'     = 'SMC_C_224X196'            | '(SMC_C_224X196)'                               | 'CAP, 22UF, +/-20%, 25V, X7R, 2220'                                               | 'NFND'    
 'CL1003489A'     | '10UF'    | '+/-20%'     = 'SMC_C_224X196'            | '(SMC_C_224X196)'                               | 'CAP, 10UF, +/-20%, 50V, X7R, 2220'                                               | 'NFND'    
 'CL1003490A'     | '3.3UF'   | '+/-10%'     = 'SMC_C_224X196'            | '(SMC_C_224X196)'                               | 'CAP, 3.3UF, +/-10%, 50V, X7R, 2220'                                              | 'NFND'    
 'CL1003491A'     | '4.7UF'   | '+/-10%'     = 'SMC_C_224X196'            | '(SMC_C_224X196)'                               | 'CAP, 4.7UF, +/-10%, 50V, X7R, 2220'                                              | 'NFND'    
 'CL1003492A'     | '6.8UF'   | '+/-10%'     = 'SMC_C_224X196'            | '(SMC_C_224X196)'                               | 'CAP, 6.8UF, +/-10%, 50V, X7R, 2220'                                              | 'NFND'    
 'CL1003493A'     | '1UF'     | '+/-10%'     = 'SMC_C_224X196'            | '(SMC_C_224X196)'                               | 'CAP, 1UF, +/-10%, 100V, X7R, 2220'                                               | 'NFND'    
 'CL1003494A'     | '1.5UF'   | '+/-10%'     = 'SMC_C_224X196'            | '(SMC_C_224X196)'                               | 'CAP, 1.5UF, +/-10%, 100V, X7R, 2220'                                             | 'NFND'    
 'CL1003495A'     | '2.2UF'   | '+/-10%'     = 'SMC_C_224X196'            | '(SMC_C_224X196)'                               | 'CAP, 2.2UF, +/-10%, 100V, X7R, 2220'                                             | 'NFND'    
 'CL1003496A'     | '3.3UF'   | '+/-10%'     = 'SMC_C_224X196'            | '(SMC_C_224X196)'                               | 'CAP, 3.3UF, +/-10%, 100V, X7R, 2220'                                             | 'NFND'    
 'CL1003497A'     | '4.7UF'   | '+/-10%'     = 'SMC_C_224X196'            | '(SMC_C_224X196)'                               | 'CAP, 4.7UF, +/-10%, 100V, X7R, 2220'                                             | 'NFND'    
 'CL1003498A'     | '4.7UF'   | '+/-20%'     = 'SMC_C_224X196'            | '(SMC_C_224X196)'                               | 'CAP, 4.7UF, +/-20%, 100V, X7R, 2220'                                             | 'NFND'    
 'CL1003499A'     | '1UF'     | '+/-10%'     = 'SMC_C_224X196'            | '(SMC_C_224X196)'                               | 'CAP, 1UF, +/-10%, 250V, X7R, 2220'                                               | 'NFND'    
 'CL1003500A'     | '1UF'     | '+/-20%'     = 'SMC_C_224X196'            | '(SMC_C_224X196)'                               | 'CAP, 1UF, +/-20%, 250V, X7R, 2220'                                               | 'NFND'    
 'CL1003501A'     | '330NF'   | '+/-10%'     = 'SMC_C_224X196'            | '(SMC_C_224X196)'                               | 'CAP, 330NF, +/-10%, 250V, X7R, 2220'                                             | 'NFND'    
 'CL1003502A'     | '470NF'   | '+/-20%'     = 'SMC_C_224X196'            | '(SMC_C_224X196)'                               | 'CAP, 470NF, +/-20%, 250V, X7R, 2220'                                             | 'NFND'    
 'CL1003503A'     | '220NF'   | '+/-10%'     = 'SMC_C_224X196'            | '(SMC_C_224X196)'                               | 'CAP, 220NF, +/-10%, 630V, X7R, 2220'                                             | 'NFND'    
 'CL1003504A'     | '47UF'    | '-20/+80%'    = 'SMC_C_224X196'            | '(SMC_C_224X196)'                               | 'CAP, 47UF, -20/+80%, 25V, Y5V, 2220'                                             | 'NFND'    
 'CL1003505A'     | '22UF'    | '-20/+80%'    = 'SMC_C_224X196'            | '(SMC_C_224X196)'                               | 'CAP, 22UF, -20/+80%, 50V, Y5V, 2220'                                             | 'NFND'    
 'CL1003506A'     | '1UF'     | '+/-10%'     = 'SMC_0402R'                | '(SMC_0402R_C)'                                 | 'CAP, 1UF, +/-10%, 10V, X5R, 0402'                                                | 'NFND'    
 'G101-00020-01'  | '1UF'     | '+/-10%'     = 'SMC_0402R'                | '(SMC_0402R_C)'                                 | 'CAP, 1UF, +/-10%, 10V, X5R, 0402'                                                | 'NFND'    
 'CL1001396A'     | '18PF'    | '+/-5%'      = 'SMC_0402R'                | '(SMC_0402R_C)'                                 | 'CAP, 18PF, +/-5%, 50V, C0G, 0402'                                                | 'NFND'    
 'G105-0A180-FJ'  | '18PF'    | '+/-5%'      = 'SMC_0402R'                | '(SMC_0402R_C)'                                 | 'CAP, 18PF, +/-5%, 50V, C0G, 0402'                                                | 'NFND'    
 'CL1001386A'     | '100PF'   | '+/-5%'      = 'SMC_0402R'                | '(SMC_0402R_C)'                                 | 'CAP, 100PF, +/-5%, 50V, C0G, 0402'                                               | 'NFND'    
 'CL1001389A'     | '22PF'    | '+/-5%'      = 'SMC_0402R'                | '(SMC_0402R_C)'                                 | 'CAP, 22PF, +/-5%, 50V, C0G, 0402'                                                | 'NFND'    
 'G101-00025-01'  | '22PF'    | '+/-5%'      = 'SMC_0402R'                | '(SMC_0402R_C)'                                 | 'CAP, 22PF, +/-5%, 50V, C0G, 0402'                                                | 'NFND'    
 'CL1001399A'     | '47PF'    | '+/-5%'      = 'SMC_0402R'                | '(SMC_0402R_C)'                                 | 'CAP, 47PF, +/-5%, 50V, C0G, 0402'                                                | 'NFND'    
 'G105-0A470-FJ'  | '47PF'    | '+/-5%'      = 'SMC_0402R'                | '(SMC_0402R_C)'                                 | 'CAP, 47PF, +/-5%, 50V, C0G, 0402'                                                | 'NFND'    
 'CL1001383A'     | '6.8PF'   | '+/-0.5PF'    = 'SMC_0402R'                | '(SMC_0402R_C)'                                 | 'CAP, 6.8PF, +/-0.5PF, 50V, C0G, 0402'                                            | 'NFND'    
 'CL1001393A'     | '1000PF'  | '+/-10%'     = 'SMC_0402R'                | '(SMC_0402R_C)'                                 | 'CAP, 1000PF, +/-10%, 16V, X7R, 0402'                                             | 'NFND'    
 'G105-0B102-DK'  | '1000PF'  | '+/-10%'     = 'SMC_0402R'                | '(SMC_0402R_C,C0402-0P8MM-45DG)'                                 | 'CAP, 1000PF, +/-10%, 16V, X7R, 0402'                                             | 'NFND'    
 'CL1001391A'     | '10NF'    | '+/-10%'     = 'SMC_0402R'                | '(SMC_0402R_C)'                                 | 'CAP, 10NF, +/-10%, 16V, X7R, 0402'                                               | 'NFND'    
 'CL1001387A'     | '100NF'   | '+/-10%'     = 'SMC_0402R'                | '(SMC_0402R_C)'                                 | 'CAP, 100NF, +/-10%, 16V, X7R, 0402'                                              | 'NFND'    
 'CL1001394A'     | '22NF'    | '+/-10%'     = 'SMC_0402R'                | '(SMC_0402R_C)'                                 | 'CAP, 22NF, +/-10%, 16V, X7R, 0402'                                               | 'NFND'    
 'CL1001395A'     | '33NF'    | '+/-10%'     = 'SMC_0402R'                | '(SMC_0402R_C)'                                 | 'CAP, 33NF, +/-10%, 16V, X7R, 0402'                                               | 'NFND'    
 'CL1001398A'     | '10UF'    | '+/-20%'     = 'SMC_0603R'                | '(SMC_0603R)'                                   | 'CAP, 10UF, +/-20%, 6.3V, X5R, 0603'                                              | 'NFND'    
 'CL1001384A'     | '4.7UF'   | '+/-10%'     = 'SMC_0603R'                | '(SMC_0603R)'                                   | 'CAP, 4.7UF, +/-10%, 10V, X5R, 0603'                                              | 'NFND'    
 'CL1001392A'     | '8PF'     | '+/-0.25PF'    = 'SMC_0402R'                | '(SMC_0402R_C)'                                 | 'CAP, 8PF+/-0.25PF, 50V, C0G, 0402'                                               | 'NFND'    
 'CL1001390A'     | '1.2PF'   | '+/-0.05PF'    = 'SMC_0402R'                | '(SMC_0402R_C)'                                 | 'CAP, 50V, C0G, 1.2PF+/-0.05PF, 0402, HIGH-Q'                                     | 'NFND'    
 'CL1001378A'     | '470NF'   | '10%'        = 'SMC_0402R'                | '(SMC_0402R_C)'                                 | 'CAP, 470NF, 10%, 10V, X5R, 0402'                                                 | 'NFND'    
 'CL1001379A'     | '82PF'    | '5%'         = 'SMC_0402R'                | '(SMC_0402R_C)'                                 | 'CAP, 82PF, 5%, 50V, C0G, 0402'                                                   | 'NFND'    
 'CL1001380A'     | '5.6PF'   | '0.5PF'      = 'SMC_0603R'                | '(SMC_0603R)'                                   | 'CAP, 5.6PF, +/-0.5PF, 50V, C0G, 0603'                                            | 'NFND'    
 'CL1001381A'     | '2PF'     | '0.25PF'     = 'SMC_0402R'                | '(SMC_0402R_C)'                                 | 'CAP, 2PF, +/-0.25PF, 50V, C0G, 0402'                                             | 'NFND'    
 'CL1001388A'     | '3.3NF'   | '10%'        = 'SMC_0402R'                | '(SMC_0402R_C)'                                 | 'CAP, 16V, X7R, 3.3NF+/-10%, 0402'                                                | 'NFND'    
 'CL1003537A'     | '82NF'    | '10%'        = 'SMC_0402R'                | '(SMC_0402R_C)'                                 | 'CAP, 82NF, +/-10%, 16V, X7R, 0402'                                               | 'NFND'    
 'CL1003562A'     | '3900PF'  | '5%'         = 'SMC_0603R'                | '(SMC_0603R)'                                   | 'CAP, 3900PF, +/-5%, 50V, UJ, 0603'                                               | ''        
 'CL1003585A'     | '0.82UF'  | '10%'        = 'SMC_0603R'                | '(SMC_0603R)'                                   | 'CAPACITORS, 0.82UF, 10V, +/-10%, 0603, X5R'                                      | 'NFND'    
 'CL1003586A'     | '4700PF'  | '10%'        = 'SMC_1812R'                | '(SMC_1812R)'                                   | 'CAP, 4700PF, +/-10%, 2000V, X7R, 1812'                                           | 'NFND'    
 'CL1003603A'     | '10UF'    | '10%'        = 'SMC_0805R'                | '(SMC_0805R)'                                   | 'CAP, 10UF, 10V, +/-10%, X7R, 0805'                                               | 'NFND'    
 'CL1003611A'     | '0.15UF'  | '10%'        = 'SMC_0603R'                | '(SMC_0603R)'                                   | 'CAP, 0.15UF, +-10%, 10VDC, X7R, 0603'                                            | 'NFND'    
 'CL1003610A'     | '0.39UF'  | '10%'        = 'SMC_0603R'                | '(SMC_0603R)'                                   | 'CAP, 0.39UF, +-10%, 16VDC, X7R, 0603'                                            | 'NFND'    
 'CL1003646A'     | '1000PF'  | '5%'         = 'SMC_0402R'                | '(SMC_0402R_C)'                                 | 'CAP, 1000PF, +/-5%, 50V, X7R, 0402'                                              | 'NFND'    
 'CL1003650A'     | '1500PF'  | '10%'        = 'SMC_0402R'                | '(SMC_0402R_C)'                                 | 'CAP, 1500PF, +/-10%, 50V, X7R, CER, 0402'                                        | 'NFND'    
 'CL1003668A'     | '33PF'    | '5%'         = 'SMC_1808'                 | '(SMC_1808)'                                    | 'CAP, 33PF, Y2, SL, 5%, 250V, 1808'                                               | 'NFND'    
 'CL1003669A'     | '680PF'   | '10%'        = 'SMC_1808'                 | '(SMC_1808)'                                    | 'CAP, 680PF, Y2, X7R, 10%, 250V, 1808'                                            | 'NFND'    
 'CL1003684A'     | '0.22UF'  | '10%'        = 'SMC_0402R'                | '(SMC_0402R_C)'                                 | 'CAP, 0.22UF, +/-10%, 10V, X5R, 0402'                                             | 'NFND'    
 'CL1003685A'     | '0.22UF'  | '10%'        = 'SMC_0603R'                | '(SMC_0603R)'                                   | 'CAP, 0.22UF, +/-10%, 25V, X7R, 0603'                                             | 'NFND'    
 'CL1003692A'     | '1UF'     | '5%'         = 'R2_C276_P886'             | '(R2_C276_P886)'                                | 'CAP, FILM, 1UF, 5%, -55/+105C, 250V-85C, 150V-105C, LEAD SPACING=22.5MM'         | 'NFND'    
 'CL1003698A'     | '0.47UF'  | '5%'         = 'R2_C335_P591'             | '(R2_C335_P591)'                                | 'CAP, 0.47UF, +/-5%, 160VAC, METALLIZED POLYPROPYLENE FILM, -40~125C'             | 'NFND'    
 'CL1003699A'     | '0.22UF'  | '5%'         = 'R2_C236_P591'             | '(R2_C236_P591)'                                | 'CAP, 0.22UF, +/-5%, 160VAC, METALLIZED POLYPROPYLENE FILM, -40~125C'             | 'NFND'    
 'CL1003700A'     | '0.33UF'  | '5%'         = 'R2_C276_P591'             | '(R2_C276_P591)'                                | 'CAP, 0.33UF, +/-5%, 160VAC, METALLIZED POLYPROPYLENE FILM, -40~125C'             | 'NFND'    
 'CL1003701A'     | '0.68UF'  | '5%'         = 'R2_C354_P591'             | '(R2_C354_P591)'                                | 'CAP, 0.68UF, +/-5%, 160VAC, METALLIZED POLYPROPYLENE FILM, -40~125C'             | 'NFND'    
 'CL1003704A'     | '0.47UF'  | '5%'         = 'SMC_C_511X472'            | '(SMC_C_511X472)'                               | 'CAP, METALLIZED POLYESTER FILM, 0.47UF, 5%, 160V AC, -40~125C'                   | 'NFND'    
 'CL1003705A'     | '0.47UF'  | '5%'         = 'SMC_C_5040R'              | '(SMC_C_5040R)'                                 | 'CAP, METALLIZED POLYPROPYLENE NAPHTALATE FILM, 0.47UF, 5%, 160V AC, -55~125C'    | 'NFND'    
 'CL1003709A'     | '0.47UF'  | '5%'         = 'R2_C236_P591_V1'          | '(R2_C236_P591_V1)'                             | 'CAP, 0.47UF, 160V AC, 250V DC, +/-5%, 6X12X17.5MM'                               | 'NFND'    
 'CL1003725A'     | '4700PF'  | '10%'        = 'R2_C768X197_P394_H925'    | '(R2_C768X197_P394_H925)'                       | 'CAP, MID-HIGH VOLTAGE CER, 4700PF, 2000V, 10%, LEAD TYPE'                        | 'NFND'    
 'CL1003727A'     | '0.22UF'  | '10%'        = 'SMC_1206R_H071'           | '(SMC_1206R_H071)'                              | 'CAP, .22UF, 25V, 10%, X7R, 1206'                                                 | 'NFND'    
 'CL1003726A'     | '4700PF'  | '20%'        = 'R2_C610X197_P394_H768'    | '(R2_C610X197_P394_H768_CST)'                   | 'CAP, MID-HIGH VOLTAGE CER, 4700PF, 250VAC, 20%, LEAD TYPE'                       | 'NFND'    
 'CL1003723A'     | '0.1UF'   | '20%'        = 'R2_C591X315_P492_H610'    | '(R2_C591X315_P492_H610_CST)'                   | 'CAP .X-2 MET POLY FILM CAP, .1UF, 300VAC, 20%, 15MM*8MM*15MM'                    | 'NFND'    
 'CL1003722A'     | '0.047UF' | '20%'        = 'R2_C591X236_P492_H531'    | '(R2_C591X236_P492_H531_CST)'                   | 'CAP, X-2 MET POLY FILM, .047UF, 300VAC, 20%, 15MM*6MM*13MM'                      | 'NFND'    
 'CL1003747A'     | '0.47UF'  | '20%'        = 'R2_C1004X335_P8858_H709'  | '(R2_C591X236_P492_H531)'                       | 'CAP, X-2 MET POLY FILM, .47UF, 250/275V AC, 20%'                                 | 'NFND'    
 'CL1003748A'     | '1000PF'  | '10%'        = 'R2_C354X197_P197_H512'    | '(R2_C354X197_P197_H512)'                       | 'CAP, MID-HIGH VOLTAGE, 1000PF, 10%, 1000V, LEADED TYPE'                          | 'NFND'    
 'CL1003753A'     | '1000PF'  | '10%'        = 'R2_C472X236_P295_H630'    | '(R2_C472X236_P295_H630_CST)'                   | 'CAP, MID-HIGH VOLTAGE, 1000PF, 10%, 3000V, LEADED TYPE'                          | 'NFND'    
 'CL1003754A'     | '2200PF'  | '10%'        = 'R2_C650X236_P394_H807'    | '(R2_C650X236_P394_H807)'                       | 'CAP, MID-HIGH VOLTAGE, 2200PF, 10%, 3000V, LEADED TYPE'                          | 'NFND'    
 'CL1003799A'     | '2200PF'  | '10%'        = 'R2_C669X236_P295_H787'    | '(R2_C669X236_P295_H787)'                       | 'CAP, HIGH VOLTAGE, 2200PF, 10%, 3.15KV, LEADED TYPE'                             | 'NFND'    
 'CL1003800A'     | '1000PF'  | '10%'        = 'R2_C512X236_P295_H630'    | '(R2_C472X236_P295_H630_CST)'                   | 'CAP, HIGH VOLTAGE, 1000PF, 10%, 3.15KV, LEADED TYPE'                             | 'NFND'    
 'CL1003805A'     | '1000PF'  | '10%'        = 'SMC_1808R_H087'           | '(SMC_1808R_H087)'                              | 'CAP, 1000PF, 250V AC, X7R, 10%, 1808'                                            | 'NFND'    
 'CL1003807A'     | '0.1UF'   | '5%'         = 'R2_C492X224_P3937_H618'   | '(R2_C492X224_P3937_H618)'                      | 'CAP, 0.1UF, 220V AC, 400V DC, +/-5%, 5.7 X 15.7 X 12.5MM'                        | 'NFND'    
 'CL1003806A'     | '0.1UF'   | '5%'         = 'R2_C689X311_P5905_H728'   | '(R2_C689X311_P5905_H728)'                      | 'CAP, 0.1UF, 250V AC, 630V DC, +/-5%, 7.9 X 17.0 X 17.5MM'                        | 'NFND'    
 'CL1003804A'     | '0.47UF'  | '5%'         = 'R2_C689X331_P5905_H807'   | '(R2_C689X331_P5905_H807)'                      | 'CAP, 0.47UF, 220V AC, 400V DC, +/-5%, 8.4 X 20.5  X 17.5MM'                      | 'NFND'    
 'CL1003811A'     | '2200PF'  | '20%'        = 'R2_C315X197_P295_H433'    | '(R2_C315X197_P295_H433)'                       | 'CAP, Y2 CLASS SAFETY CAPACITOR, 2200PF, 20%, AC 2.6KV, PITCH 7.5MM, LEADED TYPE' | 'NFND'    
 'CL1003812A'     | '1000PF'  | '20%'        = 'R2_C276X197_P295_H394'    | '(R2_C276X197_P295_H394)'                       | 'CAP, Y2 CLASS SAFETY CAPACITOR, 1000PF, 20%, AC 2.6KV, PITCH 7.5MM, LEADED TYPE' | 'NFND'    
 'CL1003813A'     | '1000PF'  | '20%'        = 'R2_C276X276_P394_H394'    | '(R2_C276X276_P394_H394_CST)'                   | 'CAP, Y1 CLASS SAFETY CAPACITOR, 1000PF, 20%, AC 4KV, PITCH 10MM, LEADED TYPE'    | 'NFND'    
 'CL1003814A'     | '2200PF'  | '20%'        = 'R2_C354X276_P394_H472'    | '(R2_C354X276_P394_H472_CST)'                   | 'CAP, Y1 CLASS SAFETY CAPACITOR, 2200PF, 20%, AC 4KV, PITCH 10MM, LEADED TYPE'    | 'NFND'    
 'CL1003815A'     | '0.47UF'  | '20%'        = 'R2_C303X157_P197_H591'    | '(R2_C303X157_P197_H591)'                       | 'CAP, 0.47UF, 630V DC, +/-20%, 7.7 X 13.0 X 4MM, PITCH 5MM, LEADED TYPE'          | 'NFND'    
 'CL1003816A'     | '0.1UF'   | '10%'        = 'R2_C295X124_P197_H315'    | '(R2_C295X124_P197_H315)'                       | 'CAP, 0.1UF, 630V DC, 10%, 7.5 X 5.5 X 3.15MM, PITCH 5MM, LEADED TYPE'            | 'NFND'    
 'G101-10007-01'  | '0.1UF'   | '10%'        = 'SMC_0402R_H022'           | '(SMC_0402R_C_H022)'                            | 'CAP,0.1UF,10%,10V,X7R,0402'                                                      | 'NFND'    
 'G101-10005-01'  | '100PF'   | '5%'         = 'SMC_0402R_H022'           | '(SMC_0402R_C_H022)'                            | 'CAP, 100PF, 5%, 50V, C0G, 0402 '                                                 | 'NFND'    
 'G101-10008-01'  | '100UF'   | '20%'        = 'SMC_1210R_H106'           | '(SMC_1210R_H106)'                              | 'CAP,100UF,X5R,20%,6.3V,1210 '                                                    | 'NFND'    
 'CL1003817A'     | '0.047UF' | '10%'        = 'R2_C709X197_P591_H413'    | '(R2_C709X197_P591_H413)'                       | 'CAP, X1 CLASS, 0.047UF, 330VAC, 10%, PITCH 15MM, 5.0 X10.5 X18.0, LEADED TYPE'   | 'NFND'    
 'CL1003818A'     | '0.1UF'   | '10%'        = 'R2_C709X236_P591_H433'    | '(R2_C709X236_P591_H433)'                       | 'CAP, 0.1UF, 630V DC, +/-10%, 6.0 X 11.0 X 18.0MM, PITCH 15MM, LEADED TYPE'       | 'NFND'    
 'CL1003819A'     | '0.47UF'  | '10%'        = 'R2_C709X433_P591_H728'    | '(R2_C709X433_P591_H728)'                       | 'CAP, 0.47UF, 630V DC, +/-10%, 11.0 X 18.5 X 18.0MM, PITCH 15MM, LEADED TYPE'     | 'NFND'    
 'CL1003824A'     | '0.47UF'  | '10%'        = 'R2_C1024X366_P886_H768'   | '(R2_C1024X366_P886_H768)'                      | 'CAP, 0.47UF, 630V DC, +/-10%, 26 X 9.3 X 18.5MM, PITCH 22.5MM, LEADED TYPE'      | 'NFND'    
 'CL1003825A'     | '0.1UF'   | '10%'        = 'R2_C728X248_P591_H591'    | '(R2_C728X248_P591_H591)'                       | 'CAP, 0.1UF, 630V DC, +/-10%, 18.5 X 6.3 X 14MM, PITCH 15MM, LEADED TYPE'         | 'NFND'    
 'CL1003826A'     | '0.47UF'  | '10%'        = 'R2_C1043X335_P886_H650'   | '(R2_C1043X335_P886_H650)'                      | 'CAP, 0.47UF, 630V DC, +/-10%, 26.5 X 8.5 X 16.5MM, PITCH 22.5MM, LEADED TYPE'    | 'NFND'    
 'G101-10012-01'  | '10UF'    | '10%'        = 'SMC_C_1210'               | '(SMC_C_1210)'                                  | 'CAP, 10UF, MONOLITHIC, CERAMIC, X7R, 10%, 35V, SMD, 1210'                        | 'NFND'    
 'G101-10016-01'  | '2.2UF'   | '10%'        = 'SMC_0402R_H022'           | '(SMC_0402R_C_H022)'                            | 'CAP, 2.2U, 10%, X5R, 6.3V, 0402'                                                 | 'NFND'    
 'G101-10017-01'  | '10UF'    | '10%'        = 'SMC_0603R_H035'           | '(SMC_0603R_H035)'                              | 'CAP, 10U, 10%, X5R, 10V, 0603'                                                   | 'NFND'    
 'G101-10018-01'  | '4.7UF'   | '20%'        = 'SMC_0402R_H022'           | '(SMC_0402R_C_H022)'                            | 'CAP, 4.7U, 20%, X5R, 6.3V, 0402'                                                 | ''        
 'G101-10022-01'  | '0.1UF'   | '10%'        = 'SMC_0603R_H035'           | '(SMC_0603R_H035)'                              | 'CAP, 0.1U, 10%, B, 50V, 0603'                                                    | 'NFND'    
 'G101-10023-01'  | '22UF'    | '10%'        = 'SMC_1210R_H106'           | '(SMC_1210R_H106)'                              | 'CAP, 22U, 20%, B, 25V, 1210'                                                     | 'NFND'    
 'G106-0A151-FJ'  | '150PF'   | '5%'         = 'SMC_0603R_H035'           | '(SMC_0603R_H035)'                              | 'CAP,150PF,+/-5%,50V,C0G,0603'                                                    | 'NFND'    
 'G107-0B154-FK'  | '0.150UF' | '10%'        = 'SMC_0805R_H053'           | '(SMC_0805R_H053)'                              | 'CAP,0.150UF,10%,50V,X7R,0805'                                                    | 'NFND'    
 'G106-0B472-FM'  | '4700PF'  | '20%'        = 'SMC_0603R_H035'           | '(SMC_0603R_H035)'                              | 'CAP,4700PF,20%,50V,X7R,0603'                                                     | 'NFND'    
 'G105-0A220-FJ'  | '22PF'    | '5%'         = 'SMC_0402R_H022'           | '(SMC_0402R_C_H022)'                            | 'CAP,22PF,5%,50V,C0G,0402'                                                        | 'NFND'    
 'G106-0C103-FK'  | '10NF'    | '10%'        = 'SMC_0603R_H035'           | '(SMC_0603R_H035)'                              | 'CAP,10NF,10%,50V,X5R,0603'                                                       | 'NFND'    
 'G105-0A120-FJ'  | '12PF'    | '5%'         = 'SMC_0402R_H022'           | '(SMC_0402R_C_H022)'                            | 'CAP,12PF,5%,50V,C0G,CER,0402'                                                    | 'NFND'    
 'G106-0A121-FK'  | '120PF'   | '10%'        = 'SMC_0603R_H035'           | '(SMC_0603R_H035)'                              | 'CAP,120PF,10%,50V,C0G,CER,0603'                                                  | 'NFND'    
 'G106-0B562-FK'  | '5.6NF'   | '10%'        = 'SMC_0603R_H035'           | '(SMC_0603R_H035)'                              | 'CAP X7R 5.6NF 10% 50V 0603'                                                      | 'NFND'    
 'G106-0B393-DK'  | '39NF'    | '10%'        = 'SMC_0603R_H035'           | '(SMC_0603R_H035)'                              | 'CAP X7R 39NF 10% 16V 0603'                                                       | 'NFND'    
 'G106-0B123-DK'  | '12NF'    | '10%'        = 'SMC_0603R_H035'           | '(SMC_0603R_H035)'                              | 'CAP X7R 12NF 10% 16V 0603'                                                       | 'NFND'    
 'G106-0B822-EK'  | '8.2NF'   | '10%'        = 'SMC_0603R_H035'           | '(SMC_0603R_H035)'                              | 'CAP X7R 8.2NF 10% 25V 0603'                                                      | 'NFND'    
 'G106-0A331-FK'  | '330PF'   | '10%'        = 'SMC_0603R_H035'           | '(SMC_0603R_H035)'                              | 'CAP,330PF,10%,50V,C0G,0603'                                                      | 'NFND'    
 'G106-0A221-EK'  | '220PF'   | '10%'        = 'SMC_0603R_H035'           | '(SMC_0603R_H035)'                              | 'CAP,220PF,10%,25V,COG,0603'                                                      | 'NFND'    
 'G106-0B683-FK'  | '68000PF' | '10%'        = 'SMC_0603R_H035'           | '(SMC_0603R_H035)'                              | 'CAP,68000PF,10%,50V,X7R,0603'                                                    | 'REJECTED'
 'G106-0A391-FJ'  | '390PF'   | '5%'         = 'SMC_0603R_H035'           | '(SMC_0603R_H035)'                              | 'CAP,390PF,5%,50V,C0G,0603'                                                       | 'NFND'    
 'G106-0A101-FJ'  | '100PF'   | '5%'         = 'SMC_0603R_H035'           | '(SMC_0603R_H035)'                              | 'CAP,100PF,5%,50V,C0G,0603'                                                       | 'NFND'    
 'G106-0B471-FM'  | '470PF'   | '20%'        = 'SMC_0603R_H035'           | '(SMC_0603R_H035)'                              | 'CAP,470PF,20%,50V,X7R,0603'                                                      | 'NFND'    
 'G106-0B222-FM'  | '2200PF'  | '20%'        = 'SMC_0603R_H035'           | '(SMC_0603R_H035)'                              | 'CAP,2200PF,20%,50V,X7R,0603'                                                     | 'NFND'    
 'G106-0A151-FK'  | '150PF'   | '10%'        = 'SMC_0603R_H035'           | '(SMC_0603R_H035)'                              | 'CAP,150PF,NPO,10%,50V,CER,0603'                                                  | 'NFND'    
 'G107-0C226-DK'  | '22UF'    | '10%'        = 'SMC_0805R_H057'           | '(SMC_0805R_H057)'                              | 'CAP,22UF,X5R,10%,16V,CER,0805'                                                   | 'NFND'    
 'G108-0C107-CM'  | '100UF'   | '20%'        = 'SMC_1206R_H071'           | '(SMC_1206R_H071)'                              | 'CAP,100UF,X5R,20%,10V,CER,1206'                                                  | ''        
 'G101-10020-01'  | '15NF'    | '10%'        = 'SMC_0402R_H022'           | '(SMC_0402R_C_H022)'                            | 'CAP,15NF,10%,16V,X7R,0402'                                                       | 'NFND'    
 'G105-0B822-EK'  | '8200PF'  | '10%'        = 'SMC_0402R_H022'           | '(SMC_0402R_C_H022)'                            | 'CAP,8200PF,10%,25V,X7R,0402'                                                     | 'NFND'    
 'G106-0A390-FK'  | '39PF'    | '10%'        = 'SMC_0603R_H035'           | '(SMC_0603R_H035)'                              | 'CAP,39PF,10%,50V,C0G,0603'                                                       | 'NFND'    
 'G106-0A821-FK'  | '820PF'   | '10%'        = 'SMC_0603R_H035'           | '(SMC_0603R_H035)'                              | 'CAP,820PF,10%,50V,C0G,0603'                                                      | 'NFND'    
 'G106-0A821-FJ'  | '820PF'   | '5%'         = 'SMC_0603R_H035'           | '(SMC_0603R_H035)'                              | 'CAP,820PF,5%,50V,C0G,0603'                                                       | 'NFND'    
 'G106-0B473-FK'  | '0.047UF' | '10%'        = 'SMC_0603R_H035'           | '(SMC_0603R_H035)'                              | 'CAP,0.047UF,10%,X7R,50V,0603'                                                    | 'NFND'    
 'G106-0B104-FK'  | '0.1UF'   | '10%'        = 'SMC_0603R'                | '(SMC_0603R)'                                   | 'CAP,0.1UF,10%,50V,X7R,0603'                                                      | 'NFND'    
 'G107-0C476-BM'  | '47UF'    | '20%'        = 'SMC_0805R_H057'           | '(SMC_0805R_H057)'                              | 'CAP,47UF,0805,6.3V,X5R,20%'                                                      | ''        
 'G106-0B684-EK'  | '0.68UF'  | '10%'        = 'SMC_0603R_H035'           | '(SMC_0603R_H035)'                              | 'CAP,0.68UF,10%,25V,X7R,0603'                                                     | 'NFND'    
 'G105-0B472-EK'  | '4700PF'  | '10%'        = 'SMC_0402R_H022'           | '(SMC_0402R_C_H022)'                            | 'CAP,4700PF,10%,25V,X7R,CER,0402'                                                 | 'NFND'    
 'G105-0B682-DK'  | '6800PF'  | '10%'        = 'SMC_0402R_H022'           | '(SMC_0402R_C_H022)'                            | 'CAP,6800PF,+/-10%,16V,X7R,0402'                                                  | 'NFND'    
 'G108-0B105-GK'  | '1UF'     | '10%'        = 'SMC_1206R_H071'           | '(SMC_1206R_H071)'                              | 'CAP, 1UF, +/-10%, 100V, X7R, 1206'                                               | 'NFND'    
 'G105-0C224-DK'  | '0.22UF'  | '10%'        = 'SMC_0402R'                | '(SMC_0402R_C)'                                 | 'CAP,0.22UF,10%,16V,X5R,0402'                                                     | 'NFND'    
 'G105-0B471-FK'  | '470PF'   | '10%'        = 'SMC_0402R_H022'           | '(SMC_0402R_C_H022)'                            | 'CAP,470PF,10%,50V,X7R,0402'                                                      | 'NFND'    
 'G101-10044-01'  | '22NF'    | '10%'        = 'SMC_1210R_H091'           | '(SMC_1210R_H091)'                              | 'CAP, 22NF, 10%, 1000V, X7R, 1210'                                                | 'NFND'    
 'G108-0B153-JK'  | '15NF'    | '10%'        = 'SMC_1206R_H049'           | '(SMC_1206R_H049)'                              | 'CAP, 15NF, 10%, 250V, X7R, 1206'                                                 | 'NFND'    
 'G101-10045-01'  | '470PF'   | '5%'         = 'SMC_1206R_H037'           | '(SMC_1206R_H037)'                              | 'CAP, 470PF, 5%, 630V, C0G, 1206'                                                 | 'NFND'    
 'G105-0A151-FJ'  | '150PF'   | '5%'         = 'SMC_0402R_H022'           | '(SMC_0402R_C_H022)'                            | 'CAP,150P,5%,50V,C0G,0402'                                                        | 'NFND'    
 'G105-0A270-FJ'  | '27PF'    | '5%'         = 'SMC_0402R'                | '(SMC_0402R_C)'                                 | 'CAP,27PF,5%,50V,C0G,0402'                                                        | 'NFND'    
 'G104-0C103-CK'  | '0.01UF'  | '10%'        = 'SMC_0201R'                | '(SMC_0201R_C)'                                 | 'CAP,0.01UF,10%,10V,X5R,0201'                                                     | 'NFND'    
 'G104-0C104-BK'  | '0.1UF'   | '10%'        = 'SMC_0201R'                | '(SMC_0201R_C)'                                 | 'CAP,0.1UF,10%,6.3V,X5R,CER,0201'                                                 | ''        
 'G105-0A560-FJ'  | '56PF'    | '5%'         = 'SMC_0402R_H022'           | '(SMC_0402R_C_H022)'                            | 'CAP, 56PF, +/-5%, 50V, C0G, 0402'                                                | 'NFND'    
 'G108-0B335-FK'  | '3.3UF'   | '10%'        = 'SMC_1206R_H067'           | '(SMC_1206R_H067)'                              | 'CAP,3.3UF,10%,50V,X7R,1206'                                                      | 'NFND'    
 'G106-0B105-EK'  | '1UF'     | '10%'        = 'SMC_0603R_H035'           | '(SMC_0603R_H035)'                              | 'CAP,1UF,10%,25V,X7R,0603'                                                        | 'NFND'    
 'G106-0C226-BM'  | '22UF'    | '20%'        = 'SMC_0603R_H039'           | '(SMC_0603R_H039)'                              | 'CAP,22U,20%,6.3V,X5R,0603'                                                       | ''        
 'G109-0B222-GK'  | '2.2NF'   | '10%'        = 'SMC_1210R_H037'           | '(SMC_1210R_H037)'                              | 'CAP,2.2NF, 10%,100V,X7R,1210'                                                    | 'NFND'    
 'G101-10046-01'  | '1NF'     | '10%'        = 'SMC_1210R_H057'           | '(SMC_1210R_H057)'                              | 'CAP, 1NF, 10%, 2KV,X7R, 1210'                                                    | 'NFND'    
 'G101-10047-01'  | '0.1UF'   | '15%'        = 'SMC_2220R_V1'             | '(SMC_2220R_V1)'                                | 'CAP,0.1UF, 15%,1KV,X7R, SMD 2220'                                                | ''        
 'G101-10048-01'  | '10NF'    | '5%'         = 'SMC_2220R_V1'             | '(SMC_2220R_V1)'                                | 'CAP,10NF,5%,1KV,U2J, SMD 2220'                                                   | ''        
 'G108-0B225-GK'  | '2.2UF'   | '10%'        = 'SMC_1206R_H075'           | '(SMC_1206R_H075)'                              | 'CAP,2.2UF,10%,100V,X7R ,SMD 1206'                                                | 'NFND'    
 'G105-0B332-EK'  | '3300PF'  | '10%'        = 'SMC_0402R'                | '(SMC_0402R_C)'                                 | 'CAP,3300PF,10%,25V,X7R,0402'                                                     | 'NFND'    
 'G108-0C476-EM'  | '47UF'    | '20%'        = 'SMC_1206R_H071'           | '(SMC_1206R_H071)'                              | 'CAP, 47UF, 20%, 25V, X5R, 1206'                                                  | ''        
 'G105-0B222-EK'  | '2.2NF'   | '10%'        = 'SMC_0402R_H022'           | '(SMC_0402R_C_H022)'                            | 'CAP,2.2NF,10%,25V,X7R ,SMD 0402'                                                 | 'NFND'    
 'G109-0B225-GK'  | '2.2UF'   | '10%'        = 'SMC_1210R_H087'           | '(SMC_1210R_H087)'                              | 'CAP, 2.2UF, 10%, 100V, X7R, 1210'                                                | ''        
 'G107-0B152-GK'  | '1.5NF'   | '10%'        = 'SMC_0805R_H057'           | '(SMC_0805R_H057)'                              | 'CAP,1.5NF, 10%,100V, X7R, SMD 0805'                                              | 'NFND'    
 'G108-0B682-GK'  | '6.8NF'   | '10%'        = 'SMC_1206R_H037'           | '(SMC_1206R_H037)'                              | 'CAP, 6.8NF, 10%, 100V, X7R, 1206'                                                | 'NFND'    
 'G105-0B152-DK'  | '1.5NF'   | '10%'        = 'SMC_0402R_H022'           | '(SMC_0402R_C_H022)'                            | 'CAP,1.5NF, 10%,16V, X7R, SMD 0402'                                               | 'NFND'    
 'G105-0A5R6-FC'  | '5.6PF'   | '+/-0.25PF'    = 'SMC_0402R_H022'           | '(SMC_0402R_C_H022)'                            | 'CAP,5.6PF,+/-0.25PF,50V,C0G,0402'                                                | 'NFND'    
 'G101-10049-01'  | '4.7UF'   | '10%'        = 'SMC_1210R_H087'           | '(SMC_1210R_H087)'                              | 'CAP,4.7UF,10%,100V,X7S,1210'                                                     | 'NFND'    
 'G105-0B104-FK'  | '0.1UF'   | '10%'        = 'SMC_0402R_H022'           | '(SMC_0402R_C_H022)'                            | 'CAP,0.1UF,10%,50V,X7R,CER,0402'                                                  | 'NFND'    
 'G106-0B223-FM'  | '0.022UF' | '20%'        = 'SMC_0603R_H035'           | '(SMC_0603R_H035)'                              | 'CAP,0.022UF,20%,50V,X7R,0603'                                                    | 'NFND'    
 'G105-0B182-FK'  | '1800PF'  | '10%'        = 'SMC_0402R_H022'           | '(SMC_0402R_C_H022)'                            | 'CAP,1800PF,10%,50V,X7R,0402'                                                     | 'NFND'    
 'G105-0B103-EK'  | '0.01UF'  | '10%'        = 'SMC_0402R'                | '(SMC_0402R_C)'                                 | 'CAP,0.01UF,10%,25V,X7R,CER,0402'                                                 | 'NFND'    
 'G101-10050-01'  | '47UF'    | '20%'        = 'SMC_2220R_V1_H098'        | '(SMC_2220R_V1_H098)'                           | 'CAP,47UF, 20%,16V,X7R,2220'                                                      | 'NFND'    
 'G101-10051-01'  | '33UF'    | '20%'        = 'SMC_2220R_V1_H087'        | '(SMC_2220R_V1_H087)'                           | 'CAP,33UF, 20%,16V,X7R,2220'                                                      | 'NFND'    
 'G109-0B226-DM'  | '22UF'    | '20%'        = 'SMC_1210R_H106'           | '(SMC_1210R_H106)'                              | 'CAP,22UF, 20%,16V,X7R,1210'                                                      | 'NFND'    
 'G108-0B475-EM'  | '4.7UF'   | '20%'        = 'SMC_1206R_H071'           | '(SMC_1206R_H071)'                              | 'CAP,4.7UF, 20%,25V,X7R,1206'                                                     | 'NFND'    
 'G109-0B226-EM'  | '22UF'    | '20%'        = 'SMC_1210R_H106'           | '(SMC_1210R_H106)'                              | 'CAP,22UF, 20%,25V,X7R,1210'                                                      | ''        
 'G101-10052-01'  | '100UF'   | '20%'        = 'SMC_1206R_H075'           | '(SMC_1206R_H075)'                              | 'CAP,100UF, 20%,4V,X6S,1206'                                                      | 'NFND'    
 'G101-10053-01'  | '0.1UF'   | '10%'        = 'SMC_0201R'                | '(SMC_0201R_C)'                                 | 'CAP,0.1UF, 10%,10V,X7S,0201'                                                     | 'OBSOLETE'
 'G104-0B103-CK'  | '0.01UF'  | '10%'        = 'SMC_0201R'                | '(SMC_0201R_C)'                                 | 'CAP,0.01UF, 10%,10V,X7R,0201'                                                    | ''        
 'G105-0B104-DK'  | '0.1UF'   | '10%'        = 'SMC_0402R'                | '(SMC_0402R_C)'                                 | 'CAP,0.1UF,10%,16V,X7R,CER,0402'                                                  | 'NFND'    
 'G105-0B103-DK'  | '0.01UF'  | '10%'        = 'SMC_0402R_H022'           | '(SMC_0402R_C_H022,C0402-0P8MM-45DG,C0402_BGA,C0402-1MM-TRIANGLE-S0,C0402-P8MM-S0)'           | 'CAP,0.01UF,10%,16V,X7R,0402'                                                     | ''        
 'G107-0B106-DM'  | '10UF'    | '20%'        = 'SMC_0805R_H053'           | '(SMC_0805R_H053)'                              | 'CAP,10UF,20%,16V,X7R,0805'                                                       | 'NFND'    
 'G101-10055-01'  | '47UF'    | '20%'        = 'SMC_1206R_H071'           | '(SMC_1206R_H071)'                              | 'CAP,47UF, 20%,6.3V,X6S,-55-105C,1206'                                            | 'OBSOLETE'    
 'G101-10056-01'  | '22UF'    | '20%'        = 'SMC_0805R_H057'           | '(SMC_0805R_H057)'                              | 'CAP,22UF, 20%,6.3V,X6S,-55-105C,0805'                                            | 'NFND'    
 'G106-0B225-CK'  | '2.2UF'   | '10%'        = 'SMC_0603R_H035'           | '(SMC_0603R_H035)'                              | 'CAP,2.2UF, 10%,10V,X7R,0603'                                                     | 'NFND'    
 'G109-0B476-BM'  | '47UF'    | '20%'        = 'SMC_1210R_H106'           | '(SMC_1210R_H106)'                              | 'CAP,47UF, 20%,6.3V,X7R,1210'                                                     | 'NFND'    
 'G105-0B222-FK'  | '2200PF'  | '10%'        = 'SMC_0402R_H022'           | '(SMC_0402R_C_H022)'                            | 'CAP,2200PF,10%,X7R,50V,0402'                                                     | ''        
 'G108-0B475-EK'  | '4.7UF'   | '10%'        = 'SMC_1206R_H071'           | '(SMC_1206R_H071)'                              | 'CAP,4.7UF, 10%,25V,X7R,1206'                                                     | 'NFND'    
 'G108-0B223-JK'  | '22000PF' | '10%'        = 'SMC_1206R_H051'           | '(SMC_1206R_H051)'                              | 'CAP,22000PF,250V,10%,X7R,1206'                                                   | 'NFND'    
 'G107-0B333-GK'  | '33000PF' | '10%'        = 'SMC_0805R_H053'           | '(SMC_0805R_H053)'                              | 'CAP,33000PF,10%,100V,X7R,0805'                                                   | 'NFND'    
 'G108-0B333-GK'  | '33000PF' | '10%'        = 'SMC_1206R_H049'           | '(SMC_1206R_H049)'                              | 'CAP,33000PF,10%,100V,X7R,1206'                                                   | 'NFND'    
 'G107-0C476-CM'  | '47UF'    | '20%'        = 'SMC_0805R_H057'           | '(SMC_0805R_H057)'                              | 'CAP,47UF,20%,X5R,10V,0805'                                                       | ''        
 'G101-10058-01'  | '1000PF'  | '10%'        = 'SMC_1812R_H087'           | '(SMC_1812R_H087)'                              | 'CAP, 1000PF, 10%, 3000V,X7R, 1812'                                               | 'NFND'    
 'G105-0A330-FJ'  | '33PF'    | '5%'         = 'SMC_0402R_H022'           | '(SMC_0402R_C_H022)'                            | 'CAP,33PF,5%,50V,C0G,0402'                                                        | 'NFND'    
 'G105-0C474-CK'  | '0.47UF'  | '10%'        = 'SMC_0402R'                | '(SMC_0402R_C)'                                 | 'CAP,0.47UF,10%,10V,X5R,CER,0402'                                                 | 'NFND'    
 'G105-0A680-FJ'  | '68PF'    | '5%'         = 'SMC_0402R'                | '(SMC_0402R_C)'                                 | 'CAP,68PF,5%,50V,C0G,0402'                                                        | 'NFND'    
 'G106-0B224-EK'  | '0.22UF'  | '10%'        = 'SMC_0603R'                | '(SMC_0603R)'                                   | 'CAP,0.22UF,10%,25V,X7R,0603'                                                     | 'NFND'    
 'G106-0C474-DK'  | '0.47UF'  | '10%'        = 'SMC_0603R_H035'           | '(SMC_0603R_H035)'                              | 'CAP,0.47UF,10%,16V,X5R,0603'                                                     | 'NFND'    
 'G106-0A680-FJ'  | '68PF'    | '5%'         = 'SMC_0603R_H035'           | '(SMC_0603R_H035)'                              | 'CAP,68PF,5%,50V,C0G,0603'                                                        | 'NFND'    
 'G105-0A4R7-FC'  | '4.7PF'   | '+/-0.25PF'    = 'SMC_0402R_H022'           | '(SMC_0402R_C_H022)'                            | 'CAP,4.7PF,0.25PF,50V,C0G,0402'                                                   | 'NFND'    
 'G105-0B333-DK'  | '33NF'    | '10%'        = 'SMC_0402R_H022'           | '(SMC_0402R_C_H022)'                            | 'CAP,33NF, 10%,X7R,16V,0402'                                                      | 'NFND'    
 'G101-10059-01'  | '1000PF'  | '10%'        = 'SMC_1206R_H071'           | '(SMC_1206R_H071)'                              | 'CAP,1000PF,+/-10%,2000V,X7R,1206'                                                | ''        
 'G107-0C106-EK'  | '10UF'    | '10%'        = 'SMC_0805R_H055'           | '(SMC_0805R_H055)'                              | 'CAP,10UF,10%,25V,X5R,0805'                                                       | ''        
 'G106-0B333-FK'  | '0.033UF' | '10%'        = 'SMC_0603R'                | '(SMC_0603R)'                                   | 'CAP,0.033UF,10%,50V,X7R,0603'                                                    | 'NFND'    
 'G105-0C106-BM'  | '10UF'    | '20%'        = 'SMC_0402R_H022'           | '(SMC_0402R_C_H022,C0402_BGA,C0402-0P8MM-45DG,C0402-P8MM-S0,C0402-1MM-TRIANGLE-S0)'                  | 'CAP,10UF,20%,6.3V,X5R,0402'                                                      | ''        
 'G108-0C226-DM'  | '22UF'    | '20%'        = 'SMC_1206R_H071'           | '(SMC_1206R_H071)'                              | 'CAP,TSB,22U,20%,X5R(B),16V,1206'                                                 | 'NFND'    
 'G105-0C105-BK'  | '1UF'     | '10%'        = 'SMC_0402R'                | '(SMC_0402R_C)'                                 | 'CAP,1.0UF,10%,6.3V,X5R,0402 '                                                    | 'NFND'    
 'G108-0C475-DM'  | '4.7UF'   | '20%'        = 'SMC_1206R_H075'           | '(SMC_1206R_H075)'                              | 'CAP,4.7UF,20%,16V,X5R,CER,1206'                                                  | 'NFND'    
 'G108-0C106-DM'  | '10UF'    | '20%'        = 'SMC_1206R_H071'           | '(SMC_1206R_H071)'                              | 'CAP,10UF,20%,16V,X5R,1206'                                                       | 'NFND'    
 'G108-0C107-BM'  | '100UF'   | '20%'        = 'SMC_1206R_H075'           | '(SMC_1206R_H075)'                              | 'CAP,100UF,20%,X5R,6.3V,1206'                                                     | ''        
 'G106-0C106-BM'  | '10UF'    | '20%'        = 'SMC_0603R'                | '(SMC_0603R)'                                   | 'CAP,10UF,20%,6.3V,X5R,0603'                                                      | 'NFND'    
 'G106-0C105-DK'  | '1UF'     | '10%'        = 'SMC_0603R_H035'           | '(SMC_0603R_H035)'                              | 'CAP,1UF,10%,16V,X5R,0603'                                                        | 'NFND'    
 'G108-0B104-GK'  | '0.1UF'   | '10%'        = 'SMC_1206R_H071'           | '(SMC_1206R_H071)'                              | 'CAP,0.1UF,100V,10%,X7R,1206'                                                     | 'NFND'    
 'G105-0A2R2-FC'  | '2.2PF'   | '+/-0.25PF'    = 'SMC_0402R_H022'           | '(SMC_0402R_C_H022)'                            | 'CAP,2.2PF,+/-0.25PF,C0G,50V,0402'                                                | 'NFND'    
 'G106-0A560-FJ'  | '56PF'    | '5%'         = 'SMC_0603R_H035'           | '(SMC_0603R_H035)'                              | 'CAP,56PF,5%,50V,C0G,0603'                                                        | 'NFND'    
 'G105-0A820-FJ'  | '82PF'    | '5%'         = 'SMC_0402R_H022'           | '(SMC_0402R_C_H022)'                            | 'CAP,82PF,5%,50V,C0G,0402'                                                        | 'NFND'    
 'G106-0A390-FJ'  | '39PF'    | '5%'         = 'SMC_0603R_H035'           | '(SMC_0603R_H035)'                              | 'CAP,39PF,5%,50V,C0G,0603'                                                        | 'NFND'    
 'G105-0A271-FJ'  | '270PF'   | '5%'         = 'SMC_0402R_H022'           | '(SMC_0402R_C_H022)'                            | 'CAP,270PF,5%,50V,COG,0402'                                                       | 'NFND'    
 'G105-0C224-EK'  | '0.22UF'  | '10%'        = 'SMC_0402R_H022'           | '(SMC_0402R_C_H022)'                            | 'CAP,0.22U,25V,X5R,+/-10%,0402'                                                   | 'NFND'    
 'G107-0C106-CM'  | '10UF'    | '20%'        = 'SMC_0805R_H057'           | '(SMC_0805R_H057)'                              | 'CAP,10UF,20%,10V,X5R,0805'                                                       | 'NFND'    
 'G106-0B471-FK'  | '470PF'   | '10%'        = 'SMC_0603R_H035'           | '(SMC_0603R_H035)'                              | 'CAP,470PF,10%,50V,X7R,0603'                                                      | 'NFND'    
 'G107-0C225-CK'  | '2.2UF'   | '10%'        = 'SMC_0805R_H057'           | '(SMC_0805R_H057)'                              | 'CAP,2.2UF,10%,10V,X5R,0805'                                                      | 'NFND'    
 'G106-0B104-GK'  | '0.1UF'   | '10%'        = 'SMC_0603R_H035'           | '(SMC_0603R_H035)'                              | 'CAP,0.1UF,10%,100V,X7R,0603'                                                     | ''        
 'G106-0B222-GK'  | '2200PF'  | '10%'        = 'SMC_0603R_H035'           | '(SMC_0603R_H035)'                              | 'CAP,2200PF,10%,100V,X7R,0603'                                                    | 'NFND'    
 'G106-0B332-FK'  | '3300PF'  | '10%'        = 'SMC_0603R_H035'           | '(SMC_0603R_H035)'                              | 'CAP,3300PF,10%,50V,X7R,0603'                                                     | 'NFND'    
 'G108-0C106-DK'  | '10UF'    | '10%'        = 'SMC_1206R_H071'           | '(SMC_1206R_H071)'                              | 'CAP,10UF,10%,16V,X5R,1206'                                                       | 'NFND'    
 'G101-10061-01'  | '1UF'     | '10%'        = 'SMC_0805R_H057'           | '(SMC_0805R_H057)'                              | 'CAP,1UF,10%,100V,X7S,0805'                                                       | ''        
 'G106-0A4R7-FC'  | '4.7PF'   | '+/-0.25PF'    = 'SMC_0603R_H035'           | '(SMC_0603R_H035)'                              | 'CAP,4.7PF,0.25PF,50V,NPO,0603'                                                   | 'NFND'    
 'G108-0C225-FK'  | '2.2UF'   | '10%'        = 'SMC_1206R_H071'           | '(SMC_1206R_H071)'                              | 'CAP,2.2UF,10%,50V,X5R,1206'                                                      | 'NFND'    
 'G106-0B221-FK'  | '220PF'   | '10%'        = 'SMC_0603R_H035'           | '(SMC_0603R_H035)'                              | 'CAP,220PF,10%,50V,X7R,0603'                                                      | 'NFND'    
 'G106-0A100-FJ'  | '10PF'    | '5%'         = 'SMC_0603R_H035'           | '(SMC_0603R_H035)'                              | 'CAP,10PF,5%,50V,COG,0603'                                                        | 'NFND'    
 'G107-0B224-FK'  | '0.22UF'  | '10%'        = 'SMC_0805R_H057'           | '(SMC_0805R_H057)'                              | 'CAP,0.22UF,10%,50V,X7R,0805'                                                     | 'NFND'    
 'G107-0B223-JM'  | '0.022UF' | '20%'        = 'SMC_0805R_H057'           | '(SMC_0805R_H057)'                              | 'CAP,0.022UF,20%,250V,X7R,0805'                                                   | 'NFND'    
 'G105-0B103-FK'  | '0.01UF'  | '10%'        = 'SMC_0402R_H022'           | '(SMC_0402R_C_H022)'                            | 'CAP,0.01UF,10%,50V,X7R,0402'                                                     | 'NFND'    
 'G105-0B393-DK'  | '39NF'    | '10%'        = 'SMC_0402R_H022'           | '(SMC_0402R_C_H022)'                            | 'CAP,39NF,10%,16V,X7R,0402'                                                       | ''        
 'G104-0C105-BM'  | '1UF'     | '20%'        = 'SMC_0201R'                | '(SMC_0201R_C)'                                 | 'CAP,1UF,20%,6.3V,X5R,0201'                                                       | 'NFND'    
 'G105-0A3R3-FC'  | '3.3PF'   | '+/-0.25PF'    = 'SMC_0402R_H022'           | '(SMC_0402R_C_H022)'                            | 'CAP,3.3PF,0.25PF,50V,C0G,0402'                                                   | 'NFND'    
 'G105-0A391-FJ'  | '390PF'   | '5%'         = 'SMC_0402R_H022'           | '(SMC_0402R_C_H022)'                            | 'CAP,390P,5%,C0G,50V,0402,SMT'                                                    | 'NFND'    
 'G105-0A221-FJ'  | '220PF'   | '5%'         = 'SMC_0402R'                | '(SMC_0402R_C)'                                 | 'CAP,220PF,5%,50V,COG,0402'                                                       | 'NFND'    
 'G108-0C226-EM'  | '22UF'    | '20%'        = 'SMC_1206R_H075'           | '(SMC_1206R_H075)'                              | 'CAP,22UF,20%,25V,X5R,1206'                                                       | 'NFND'    
 'G105-0A101-FJ'  | '100PF'   | '5%'         = 'SMC_0402R'                | '(SMC_0402R_C,C0402-0P8MM-45DG)'                | 'CAP,100PF,5%,50V,C0G,0402'                                                       | 'NFND'    
 'G107-0C106-CK'  | '10UF'    | '10%'        = 'SMC_0805R_H057'           | '(SMC_0805R_H057)'                              | 'CAP,10UF,10%,10V,X5R,0805'                                                       | 'NFND'    
 'G107-0B225-CK'  | '2.2UF'   | '10%'        = 'SMC_0805R'                | '(SMC_0805R)'                                   | 'CAP,2.2UF,10%,10V,X7R,0805'                                                      | 'NFND'    
 'G106-0C475-CK'  | '4.7UF'   | '10%'        = 'SMC_0603R_H035'           | '(SMC_0603R_H035)'                              | 'CAP,4.7UF,10%,10V,X5R,0603'                                                      | 'NFND'    
 'G105-0B681-FK'  | '680PF'   | '10%'        = 'SMC_0402R_H022'           | '(SMC_0402R_C_H022)'                            | 'CAP,680PF,10%,X7R,50V,0402'                                                      | 'NFND'    
 'G106-0A331-FJ'  | '330PF'   | '5%'         = 'SMC_0603R_H035'           | '(SMC_0603R_H035)'                              | 'CAP,330PF,5%,50V,COG,0603'                                                       | 'NFND'    
 'G105-0B333-EK'  | '33000PF' | '10%'        = 'SMC_0402R_H022'           | '(SMC_0402R_C_H022)'                            | 'CAP,33000PF,10%,25V,X7R,0402'                                                    | 'NFND'    
 'G105-0B153-DK'  | '15NF'    | '10%'        = 'SMC_0402R_H022'           | '(SMC_0402R_C_H022)'                            | 'CAP,15NF,10%,16V,X7R,0402'                                                       | 'NFND'    
 'G108-0B224-GK'  | '0.22UF'  | '10%'        = 'SMC_1206R_H071'           | '(SMC_1206R_H071)'                              | 'CAP,0.22UF,10%,100V,X7R,1206'                                                    | 'NFND'    
 'G106-0B103-FK'  | '0.01UF'  | '10%'        = 'SMC_0603R_H035'           | '(SMC_0603R_H035)'                              | 'CAP,0.01UF,10%,50V,X7R,0603'                                                     | 'NFND'    
 'G107-0C475-DM'  | '4.7UF'   | '20%'        = 'SMC_0805R_H057'           | '(SMC_0805R_H057)'                              | 'CAP,4.7UF,20%,16V,X5R,CER,0805'                                                  | 'NFND'    
 'G107-0C475-DK'  | '4.7UF'   | '10%'        = 'SMC_0805R_H057'           | '(SMC_0805R_H057)'                              | 'CAP,4.7UF,10%,16V,X5R,CER,0805'                                                  | 'NFND'    
 'G105-0C824-CK'  | '0.82UF'  | '10%'        = 'SMC_0402R_H022'           | '(SMC_0402R_C_H022)'                            | 'CAP,0.82UF,10%,X5R,10V,0402'                                                     | 'NFND'    
 'G106-0A270-FJ'  | '27PF'    | '5%'         = 'SMC_0603R'                | '(SMC_0603R)'                                   | 'CAP,27PF,5%,50V,C0G,0603'                                                        | 'NFND'    
 'G105-0A181-FJ'  | '180PF'   | '5%'         = 'SMC_0402R_H022'           | '(SMC_0402R_C_H022)'                            | 'CAP,180PF,5%,50V,C0G,0402'                                                       | 'NFND'    
 'G105-0B272-FK'  | '2700PF'  | '10%'        = 'SMC_0402R_H022'           | '(SMC_0402R_C_H022)'                            | 'CAP,2700PF,+/-10%,50V,X7R,0402'                                                  | 'NFND'    
 'G104-0C224-BK'  | '0.22UF'  | '10%'        = 'SMC_0201R'                | '(SMC_0201R_C)'                                 | 'CAP,0.22UF,10%,6.3V,X5R,0201'                                                    | ''        
 'G105-0C105-CK'  | '1UF'     | '10%'        = 'SMC_0402R'                | '(SMC_0402R_C)'                                 | 'CAP,1UF,10%,10V,X5R,0402'                                                        | 'NFND'    
 'G107-0C226-BM'  | '22UF'    | '20%'        = 'SMC_0805R'                | '(SMC_0805R)'                                   | 'CAP,22UF,20%,6.3V,X5R,CER,0805'                                                  | 'NFND'    
 'G106-0B104-EM'  | '0.1UF'   | '20%'        = 'SMC_0603R'                | '(SMC_0603R)'                                   | 'CAP,0.1UF,20%,25V,X7R,0603'                                                      | 'NFND'    
 'G108-0C106-EK'  | '10UF'    | '10%'        = 'SMC_C_1206'               | '(SMC_C_1206)'                                  | 'CAP,10UF,10%,25V,X5R,1206'                                                       | 'NFND'    
 'G107-0B105-EK'  | '1UF'     | '10%'        = 'SMC_0805R_H057'           | '(SMC_0805R_H057)'                              | 'CAP,1UF,10%,25V,X7R,0805'                                                        | 'NFND'    
 'G107-0B475-DK'  | '4.7UF'   | '10%'        = 'SMC_0805R_H055'           | '(SMC_0805R_H055)'                              | 'CAP,4.7UF,10%,16V,X7R,0805'                                                      | 'NFND'    
 'G105-0B103-DM'  | '0.01UF'  | '20%'        = 'SMC_0402R_H022'           | '(SMC_0402R_C_H022)'                            | 'CAP,0.01UF,20%,16V,X7R,0402'                                                     | 'NFND'    
 'G106-0B105-DK'  | '1UF'     | '10%'        = 'SMC_0603R'                | '(SMC_0603R)'                                   | 'CAP,1UF,10%,16V,X7R,CER,0603'                                                    | 'NFND'    
 'G101-10065-01'  | '0.22UF'  | '10%'        = 'SMC_0201R'                | '(SMC_0201R_C)'                                 | 'CAP,0.22UF,10%,6.3V,X6S,0201'                                                    | ''        
 'G105-0C473-DK'  | '0.047UF' | '10%'        = 'SMC_0402R'                | '(SMC_0402R_C)'                                 | 'CAP,0.047UF,10%,16V,X5R,CER,0402'                                                | 'NFND'    
 'G105-0B682-FK'  | '6800PF'  | '10%'        = 'SMC_0402R'                | '(SMC_0402R_C)'                                 | 'CAP,6800PF,10%,50V,X7R,0402'                                                     | 'NFND'    
 'G106-0A470-FJ'  | '47PF'    | '5%'         = 'SMC_0603R_H035'           | '(SMC_0603R_H035)'                              | 'CAP,TSB,47P,5%,NPO(CH1),50V,0603'                                                | 'NFND'    
 'G101-10068-01'  | '4.7NF'   | '20%'        = 'R2_C512X197_P394'         | '(R2_C512X197_P394)'                            | 'CAP,FILM,Y2,4.7NF,300VAC,20%,PP,13MMX5MMX11MM,TH'                                | ''        
 'G106-0C225-DK'  | '2.2UF'   | '10%'        = 'SMC_0603R_H035'           | '(SMC_0603R_H035)'                              | 'CAP,2.2UF, 10%,X5R,16V,0603'                                                     | 'NFND'    
 'G101-10067-01'  | '1UF'     | '10%'        = 'SMC_0402R_H024'           | '(SMC_0402R_C_H024)'                            | 'CAP,1UF,10%,6.3V,X7S,CER,0402'                                                   | ''        
 'A101-00001-MP'  | '4.7UF'   | '20%'        = 'SMC_0402R_H026'           | '(SMC_0402R_C_H026)'                            | 'CAP,4.7UF,20%,4V,X6S,CER,0402'                                                   | 'NFND'    
 'A101-00002-MP'  | '22UF'    | '20%'        = 'SMC_0805R_H057'           | '(SMC_0805R_H057)'                              | 'CAP,22UF,20%,6.3V,X7S,CER,0805'                                                  | 'NFND'    
 'A101-00003-MP'  | '47UF'    | '20%'        = 'SMC_0805R_H057'           | '(SMC_0805R_H057)'                              | 'CAP,47UF,20%,4V,X6S,CER,0805'                                                    | 'NFND'    
 'A101-00004-MP'  | '10UF'    | '20%'        = 'SMC_0603R_H039'           | '(SMC_0603R_H039)'                              | 'CAP,10UF,20%,6.3V,X7S,CER,0603'                                                  | 'NFND'    
 'G105-0B105-BK'  | '1UF'     | '10%'        = 'SMC_0402R_H022'           | '(SMC_0402R_C_H022)'                            | 'CAP,1UF,10%,6.3V,X7R,CER,0402'                                                   | ''        
 'A101-00005-MP'  | '4.7UF'   | '20%'        = 'SMC_0402R_H026'           | '(SMC_0402R_C_H026)'                            | 'CAP,4.7UF,20%,6.3V,X6S,CER,0402'                                                 | ''        
 'G105-0B223-FK'  | '22NF'    | '10%'        = 'SMC_0402R_H022'           | '(SMC_0402R_C_H022)'                            | 'CAP,22NF,10%,X7R,50V,0402'                                                       | 'NFND'    
 'G105-0C104-CK'  | '0.1UF'   | '10%'        = 'SMC_0402R'                | '(SMC_0402R_C)'                                 | 'CAP,0.1UF,10%,10V,X5R,CER,0402'                                                  | 'NFND'    
 'G106-0C105-EK'  | '1UF'     | '10%'        = 'SMC_0603R_H035'           | '(SMC_0603R_H035)'                              | 'CAP,1UF,10%,25V,X5R,CER,0603'                                                    | 'NFND'    
 'G101-10036-01'  | '22UF'    | '20%'        = 'SMC_0805R_H055'           | '(SMC_0805R_H055)'                              | 'CAP,22UF,X6S,4V,20%,0805'                                                        | 'NFND'    
 'G101-10039-01'  | '47UF'    | '20%'        = 'SMC_0805R_H057'           | '(SMC_0805R_H057)'                              | 'CAP,47UF,20%,4V,X6S,0805'                                                        | 'NFND'    
 'G105-0C105-BM'  | '1UF'     | '20%'        = 'SMC_0402R'                | '(SMC_0402R_C)'                                 | 'CAP,1UF,20%,6.3V,X5R,CER,0402'                                                   | 'NFND'    
 'G106-0C106-CM'  | '10UF'    | '20%'        = 'SMC_0603R_H039'           | '(SMC_0603R_H039)'                              | 'CAP, 10U, 20%, X5R, 10V, 0603'                                                   | ''        
 'G107-0C476-AM'  | '47UF'    | '20%'        = 'SMC_0805R'                | '(SMC_0805R)'                                   | 'CAP,47UF,20%,4V,X5R,CER,0805'                                                    | ''        
 'G105-0A471-FJ'  | '470PF'   | '5%'         = 'SMC_0402R'                | '(SMC_0402R_C)'                                 | 'CAP,470PF,5%,50V,C0G,0402'                                                       | 'NFND'    
 'G108-0C226-EK'  | '22UF'    | '10%'        = 'SMC_1206R_H071'           | '(SMC_1206R_H071)'                              | 'CAP,22UF,10%,25V,X5R,1206'                                                       | 'NFND'    
 'G108-0C476-CM'  | '47UF'    | '20%'        = 'SMC_1206R_H071'           | '(SMC_1206R_H071)'                              | 'CAP,47U,20%,X5R,10V,1206'                                                        | 'NFND'    
 'G109-0C476-DK'  | '47UF'    | '10%'        = 'SMC_C_1210'               | '(SMC_C_1210)'                                  | 'CAP,47UF,10%,16V,X5R,1210'                                                       | 'NFND'    
 'G109-0C107-BM'  | '100UF'   | '20%'        = 'SMC_C_1210'               | '(SMC_C_1210)'                                  | 'CAP,100UF,20%,6.3V,X5R,CER,1210'                                                 | 'NFND'    
 'G105-0B103-DJ'  | '10NF'    | '5%'         = 'SMC_0402R_H022'           | '(SMC_0402R_C_H022)'                            | 'CAP,10NF,5%,X7R,16V,0402'                                                        | 'NFND'    
 'G105-0B224-DK'  | '0.22UF'  | '10%'        = 'SMC_0402R_H022'           | '(SMC_0402R_C_H022)'                            | 'CAP,0.22UF,10%,X7R,16V,0402'                                                     | ''        
 'G109-0C226-EK'  | '22UF'    | '10%'        = 'SMC_1210R_H106'           | '(SMC_1210R_H106)'                              | 'CAP,22UF,10%,25V,X5R,1210'                                                       | 'NFND'    
 'G101-10071-01'  | '10UF'    | '10%'        = 'R2_C500X200_P402'         | '(R2_C500X200_P402)'                            | 'CAP,10UF,10%,100V,X7R,CER,TH'                                                    | 'NFND'    
 'G107-0C106-DK'  | '10UF'    | '10%'        = 'SMC_0805R_H053'           | '(SMC_0805R_H053)'                              | 'CAP,10U,10%,16V,X5R,0805'                                                        | 'NFND'    
 'A101-10001-CL'  | '0.2PF'   | '50%'        = 'SMC_0402R_H022'           | '(SMC_0402R_C_H022)'                            | 'CAP,0.2PF,50%,50V,COG,CER,0402'                                                  | 'NFND'    
 'G105-0B223-DK'  | '0.022UF' | '10%'        = 'SMC_0402R'                | '(SMC_0402R_C)'                                 | 'CAP,0.022UF,10%,16V,X7R,CER,0402'                                                | 'NFND'    
 'G101-10057-01'  | '12PF'    | '5%'         = 'SMC_0402R_H022'           | '(SMC_0402R_C_H022)'                            | 'CAP,12PF,5%,50V,C0H,0402'                                                        | 'NFND'    
 'G105-0A1R2-FB'  | '1.2PF'   | '+/-0.1PF'    = 'SMC_0402R_H022'           | '(SMC_0402R_C_H022)'                            | 'CAP,1.2PF,+/-0.1PF,50V,COG,CER,0402'                                             | 'NFND'    
 'G105-0A1R0-FB'  | '1.0PF'   | '+/-0.1PF'    = 'SMC_0402R_H022'           | '(SMC_0402R_C_H022)'                            | 'CAP,1.0PF,+/-0.1PF,50V,COG,CER,0402'                                             | ''        
 'G106-0B334-DK'  | '0.33UF'  | '10%'        = 'SMC_0603R_H035'           | '(SMC_0603R_H035)'                              | 'CAP,0.33UF,10%,16V,X7R,0603'                                                     | 'NFND'    
 'G101-10066-01'  | '0.22UF'  | '20%'        = 'R2_C303X157_P197_H591_V1' | '(R2_C303X157_P197_H591_V1)'                    | 'CAP,MONO,0.22UF,20%,1000V,X7R,7.7 X13.0 X4.0,P5,TH'                              | ''        
 'G105-0B104-EK'  | '0.1UF'   | '10%'        = 'SMC_0402R_H022'           | '(SMC_0402R_C_H022,C0402-1MM-TRIANGLE-S0,C0402-P8MM-S0)'                            | 'CAP,0.1UF,10%,25V,X7R,CER,0402'                                                  | ''        
 'G106-0A180-GJ'  | '18PF'    | '5%'         = 'SMC_0603R_H035'           | '(SMC_0603R_H035)'                              | 'CAP,18PF,5%,100V,C0G,CER,0603'                                                   | 'NFND'    
 'G106-0A330-GJ'  | '33PF'    | '5%'         = 'SMC_0603R_H035'           | '(SMC_0603R_H035)'                              | 'CAP,33PF,5%,100V,C0G,CER,0603'                                                   | 'NFND'    
 'G101-10063-01'  | '0.01UF'  | '10%'        = 'SMC_1210R_H059'           | '(SMC_1210R_H059)'                              | 'CAP,0.01UF,10%,1000V,X7R,CER,1210'                                               | 'NFND'    
 'G101-10064-01'  | '0.033UF' | '10%'        = 'SMC_1210R_H067'           | '(SMC_1210R_H067)'                              | 'CAP,0.033UF,10%,1000V,X7R,CER,1210'                                              | 'NFND'    
 'G108-0B106-EK'  | '10UF'    | '10%'        = 'SMC_1206R_H071'           | '(SMC_1206R_H071)'                              | 'CAP,10UF,10%,25V,X7R,CER,1206'                                                   | 'NFND'    
 'G109-0B226-EK'  | '22UF'    | '10%'        = 'SMC_1210R_H106'           | '(SMC_1210R_H106)'                              | 'CAP,22UF,10%,25V,X7R,CER,1210'                                                   | ''        
 'G109-0C226-EM'  | '22UF'    | '20%'        = 'SMC_C_1210_100THK'        | '(SMC_C_1210_100THK)'                           | 'CAP,22UF,20%,25V,X5R,1210'                                                       | 'NFND'    
 'G104-0B102-EK'  | '1000PF'  | '10%'        = 'SMC_0201R'                | '(SMC_0201R_C)'                                 | 'CAP,1000PF,10%,25V,X7R,CER,0201'                                                 | 'NFND'    
 'G101-10076-01'  | '10UF'    | '10%'        = 'SMC_1206R_H037'           | '(SMC_1206R_H037)'                              | 'CAP,10UF,10%,25V,X5R,1206'                                                       | 'NFND'    
 'G101-10077-01'  | '47UF'    | '20%'        = 'SMC_0805R_H037'           | '(SMC_0805R_H037)'                              | 'CAP,47UF,20%,6.3V,X5R,0805'                                                      | 'NFND'    
 'A108-0C336-DL'  | '33UF'    | '20%'        = 'SMC_1206R_H071'           | '(SMC_1206R_H071)'                              | 'CAP,33UF,+/-20%,6.3V,X5R,1206'                                                   | 'NFND'    
 'G107-0C226-DM'  | '22UF'    | '20%'        = 'SMC_0805R_H057'           | '(SMC_0805R_H057)'                              | 'CAP,22UF,20%,16V,X5R,0805'                                                       | ''        
 'G101-10078-01'  | '100UF'   | '20%'        = 'SMC_0805R_H057'           | '(SMC_0805R_H057)'                              | 'CAP,100UF,20%,2.5V,X5R,CER,0805'                                                 | ''        
 'G105-0A150-FJ'  | '15PF'    | '5%'         = 'SMC_0402R'                | '(SMC_0402R_C)'                                 | 'CAP,15PF,5%,50V,C0G,CER,0402'                                                    | 'NFND'    
 'G105-0A331-FJ'  | '330PF'   | '5%'         = 'SMC_0402R'                | '(SMC_0402R_C)'                                 | 'CAP,330PF,5%,50V,C0G,0402'                                                       | 'NFND'    
 'G106-0A182-FJ'  | '1800PF'  | '5%'         = 'SMC_0603R_H035'           | '(SMC_0603R_H035)'                              | 'CAP,1800 PF,5%,50V,C0G,0603'                                                     | 'NFND'    
 'G107-0B104-EK'  | '0.1UF'   | '10%'        = 'SMC_0805R_H041'           | '(SMC_0805R_H041)'                              | 'CAP,0.1UF,10%,50V,X7R,0805'                                                      | 'NFND'    
 'G107-0B105-FK'  | '1UF'     | '10%'        = 'SMC_0805R_H053'           | '(SMC_0805R_H053)'                              | 'CAP,1UF,10%,50V,X7R,0805'                                                        | 'NFND'    
 'G105-0C152-FK'  | '1500PF'  | '10%'        = 'SMC_0402R'                | '(SMC_0402R_C)'                                 | 'CAP,1500PF,10%,50V,X5R,0402'                                                     | 'NFND'    
 'G104-0B152-DK'  | '1500PF'  | '10%'        = 'SMC_0201R'                | '(SMC_0201R_C)'                                 | 'CAP,1500PF,10%,16V,X7R,0201'                                                     | ''        
 'G104-0B222-DK'  | '2200PF'  | '10%'        = 'SMC_0201R'                | '(SMC_0201R_C)'                                 | 'CAP,2200PF,10%,16V,X7R,0201'                                                     | ''        
 'G104-0B681-DK'  | '680PF'   | '10%'        = 'SMC_0201R'                | '(SMC_0201R_C)'                                 | 'CAP,680PF,10%,16V,X7R,0201'                                                      | ''        
 'G104-0B682-CK'  | '6800PF'  | '10%'        = 'SMC_0201R'                | '(SMC_0201R_C)'                                 | 'CAP,6800PF,10%,10V,X7R,CER,0201'                                                 | 'NFND'    
 'G104-0B332-CK'  | '3300PF'  | '10%'        = 'SMC_0201R'                | '(SMC_0201R_C)'                                 | 'CAP,3300PF,10%,10V,X7R,CER,0201'                                                 | 'NFND'    
 'G104-0B331-EK'  | '330PF'   | '10%'        = 'SMC_0201R'                | '(SMC_0201R_C)'                                 | 'CAP,330PF,10%,25V,X7R,0201'                                                      | 'NFND'    
 'G104-0B101-FJ'  | '100PF'   | '10%'        = 'SMC_0201R'                | '(SMC_0201R_C)'                                 | 'CAP,100PF,5%,50V,X7R,CER,0201'                                                   | 'NFND'    
 'G101-10079-01'  | '0.1UF'   | '10%'        = 'SMC_0201R'                | '(SMC_0201R_C)'                                 | 'CAP,0.1UF,10%,6.3V,X6S,0201'                                                     | ''        
 'G107-0C226-CM'  | '22UF'    | '20%'        = 'SMC_0805R_H039'           | '(SMC_0805R_H039)'                              | 'CAP, 22UF , 20%, X5R, 10V, 0805'                                                 | 'NFND'    
 'G107-0B474-DK'  | '0.47UF'  | '10%'        = 'SMC_0805R_H055'           | '(SMC_0805R_H055)'                              | 'CAP,0.47UF,10%,16V,X7R,0805'                                                     | 'NFND'    
 'G108-0C227-AM'  | '220UF'   | '20%'        = 'SMC_1206R_H075'           | '(SMC_1206R_H075)'                              | 'CAP,220UF,20%,4V,X5R,CER,1206'                                                   | ''        
 'G101-10087-01'  | '47UF'    | '20%'        = 'SMC_0805R_H037'           | '(SMC_0805R_H037)'                              | 'CAP,47UF,20%,2.5V,X6T,0805'                                                      | ''        
 'G101-10086-01'  | '10UF'    | '10%'        = 'SMC_1206R_H037'           | '(SMC_1206R_H037)'                              | 'CAP,10UF,10%,16V,X6S,1206'                                                       | 'NFND'    
 'G101-10083-01'  | '22UF'    | '20%'        = 'SMC_0805R_H057'           | '(SMC_0805R_H057)'                              | 'CAP,22UF,20%,16V,X6S,CER,0805'                                                   | ''        
 'G101-10085-01'  | '220UF'   | '20%'        = 'SMC_1206R_H075'           | '(SMC_1206R_H075)'                              | 'CAP,220UF,20%,4V,X6S,1206'                                                       | ''        
 'G101-10082-01'  | '22UF'    | '20%'        = 'SMC_0805R_H057'           | '(SMC_0805R_H057)'                              | 'CAP,22UF,20%,10V,X6S,0805'                                                       | ''        
 'G101-10081-01'  | '100UF'   | '20%'        = 'SMC_1210R_H110'           | '(SMC_1210R_H110)'                              | 'CAP,100UF,20%,6.3V,X6S,1210'                                                     | ''        
 'G101-10091-01'  | '2.2UF'   | '20%'        = 'SMC_0402R_H022'           | '(SMC_0402R_C_H022)'                            | 'CAP, 2.2UF, 20%, X6S, 6.3V, 0402'                                                | ''        
 'G101-10088-01'  | '22UF'    | '20%'        = 'SMC_0603R_H039'           | '(SMC_0603R_H039)'                              | 'CAP,22UF,20%,6.3V,X6S,0603'                                                      | ''        
 'G101-10084-01'  | '100UF'   | '20%'        = 'SMC_0805R_H057'           | '(SMC_0805R_H057)'                              | 'CAP,100UF,20%,4V,X6S,0805'                                                       | ''        
 'G101-10054-01'  | '10UF'    | '20%'        = 'SMC_0603R_H035'           | '(SMC_0603R_H035)'                              | 'CAP,10UF,20%,X6S,4V,0603'                                                        | 'NFND'    
 'G101-10090-01'  | '10UF'    | '20%'        = 'SMC_0603R_H039'           | '(SMC_0603R_H039)'                              | 'CCAP,10U,20%,6.3V,X6S,0603'                                                      | ''        
 'G101-10089-01'  | '22UF'    | '20%'        = 'SMC_1206R_H075'           | '(SMC_1206R_H075)'                              | 'CAP,22UF,20%,16V,X6S,1206'                                                       | 'NFND'    
 'G106-0C476-BM'  | '47UF'    | '20%'        = 'SMC_0603R_H039'           | '(SMC_0603R_H039)'                              | 'CAP,47UF,20%,6.3V,X5R,0603'                                                      | ''        
 'G106-0B154-EK'  | '0.15UF'  | '10%'        = 'SMC_0603R'                | '(SMC_0603R)'                                   | 'CAP,0.15UF,10%,25V,X7R,0603'                                                     | 'NFND'    
 'G105-0B474-CK'  | '0.47UF'  | '10%'        = 'SMC_0402R_H022'           | '(SMC_0402R_C_H022)'                            | 'CAP,0.47UF,10%,10V,X7R,0402'                                                     | 'NFND'    
 'G105-0C226-BM'  | '22UF'    | '20%'        = 'SMC_0402R_H028'           | '(SMC_0402R_C_H028,C0402_BGA)'                  | 'CAP,22UF,20%,6.3V,X5R,0402'                                                      | 'NFND'    
 'G105-0B392-EK'  | '3900PF'  | '10%'        = 'SMC_0402R_H022'           | '(SMC_0402R_C_H022)'                            | 'CAP,3900PF,10%,25V,X7R,0402'                                                     | 'NFND'    
 'G105-0B562-FK'  | '5600PF'  | '10%'        = 'SMC_0402R_H022'           | '(SMC_0402R_C_H022)'                            | 'CAP,5600PF,10%,50V,X7R,0402'                                                     | 'NFND'    
 'G101-10092-01'  | '0.01UF'  | '10%'        = 'SMC_1206R_H057'           | '(SMC_1206R_H057)'                              | 'CAP,0.01UF,10%,500V,X7R,CER,1206'                                                | 'NFND'    
 'G108-0B472-GK'  | '4700PF'  | '10%'        = 'SMC_1206R_H037'           | '(SMC_1206R_H037)'                              | 'CAP,4700PF,10%,100V,X7R,CER,1206'                                                | 'NFND'    
 'G108-0A101-GJ'  | '100PF'   | '5%'         = 'SMC_1206R_H035'           | '(SMC_1206R_H035)'                              | 'CAP,100PF,5%,100V,C0G,NP0,CER,1206'                                              | 'NFND'    
 'G101-10094-01'  | '8200PF'  | '5%'         = 'R2_C512X236_P394'         | '(R2_C512X236_P394)'                            | 'CAP,FILM,Y2,8200PF,5%,1000VDC,TH'                                                | ''        
 'G101-10093-01'  | '0.1UF'   | '10%'        = 'SMC_1210R_H110'           | '(SMC_1210R_H110)'                              | 'CAP,0.1UF,10%,630V,X7R,CER,1210'                                                 | 'NFND'    
 'G101-10096-01'  | '10UF'    | '10%'        = 'R2_C1240X591_P1083'       | '(R2_C1240X591_P1083)'                          | 'CAP,FILM,10UF,10%,450VDC,PITCH=27.5MM,94V0,TH'                                   | ''        
 'G101-10098-01'  | '10PF'    | '10%'        = 'R2_C335X217_P295'         | '(R2_C335X217_P295)'                            | 'CAP,10PF, 10%, 3KV, TH'                                                          | ''        
 'G101-10097-01'  | '5UF'     | '10%'        = 'R2_C1240X748_P1083'       | '(R2_C1240X748_P1083)'                          | 'CAP,FILM,5UF,10%,1100VDC,PITCH=27.5MM,94V0,TH'                                   | ''        
 'G101-10099-01'  | '100PF'   | '5%'         = 'R2_C217X138_P197'         | '(R2_C217X138_P197)'                            | 'CAP,100PF, 5%, 630V, C0G, RADIAL,TH'                                             | ''        
 'G101-10095-01'  | '4700PF'  | '20%'        = 'R2_C394X236_P295'         | '(R2_C394X236_P295)'                            | 'CAP,FILM,Y2,4700PF,20%,1KVDC,PITCH 7.5MM.TH'                                     | ''        
 'G104-00002-01'  | '1UF'     | '20%'        = 'SMC_0201R_H015'           | '(SMC_0201R_C_H015)'                            | 'CAP,1UF,20%,6.3V,X6S,0201'                                                       | ''        
 'G105-0C334-CK'  | '330NF'   | '10%'        = 'SMC_0402R_H022'           | '(SMC_0402R_C_H022)'                            | 'CAP,330NF,10%,10V,X5R,0402'                                                      | 'NFND'    
 'G106-00002-01'  | '47UF'    | '20%'        = 'SMC_0603R_H043'           | '(SMC_0603R_H043)'                              | 'CAP,47UF,20%,4V,X5R,0603'                                                        | ''        
 'G105-0C225-BK'  | '2.2UF'   | '10%'        = 'SMC_0402R_H022'           | '(SMC_0402R_C_H022)'                            | 'CAP,2.2UF,10%,6.3V,X5R,0402'                                                     | 'NFND'    
 'G105-0C225-CK'  | '2.2UF'   | '10%'        = 'SMC_0402R_H022'           | '(SMC_0402R_C_H022)'                            | 'CAP,2.2U,10%,10V,X5R,0402'                                                       | 'NFND'    
 'G104-0C104-DK'  | '0.1UF'   | '10%'        = 'SMC_0201R'                | '(SMC_0201R_C)'                                 | 'CAP,0.1UF,10%,16V,X5R,0201'                                                      | ''        
 'G104-0C105-CM'  | '1UF'     | '20%'        = 'SMC_0201R'                | '(SMC_0201R_C)'                                 | 'CAP, 1UF, +/-20%, 10V, X5R, 0201'                                                | ''        
 'G104-0B103-DK'  | '0.01UF'  | '10%'        = 'SMC_0201R'                | '(SMC_0201R_C)'                                 | 'CAP,0.01UF,10%,16V,X7R,0201'                                                     | ''        
 'G105-0C105-EK'  | '1UF'     | '10%'        = 'SMC_0402R_H024'           | '(SMC_0402R_C_H024)'                            | 'CAP, CER, 1UF, 10%, 25V, 0402, X5R, ROHS'                                        | ''        
 'G104-0C104-EK'  | '0.1UF'   | '10%'        = 'SMC_0201R'                | '(SMC_0201R_C)'                                 | 'CAP,0.1UF,10%,25V,X5R,CER,0201'                                                  | ''        
 'G104-0A101-FJ'  | '100PF'   | '5%'         = 'SMC_0201R'                | '(SMC_0201R_C)'                                 | 'CAP,100PF,5%,50V,C0G,0201'                                                       | ''        
 'G104-0C103-EK'  | '0.01UF'  | '10%'        = 'SMC_0201R'                | '(SMC_0201R_C)'                                 | 'CAP, 0.01UF, +/-10%, 25V, X5R, 0201'                                             | ''        
 'G104-0B102-DK'  | '1000PF'  | '10%'        = 'SMC_0201R'                | '(SMC_0201R_C)'                                 | 'CAP, 1000PF, +/-10%, 16V, X7R, 0201'                                             | ''        
 'G104-0B102-FK'  | '1000PF'  | '10%'        = 'SMC_0201R'                | '(SMC_0201R_C)'                                 | 'CAP,1000PF,10%,50V,X7R,0201'                                                     | ''        
 'G104-0A221-FJ'  | '220PF'   | '5%'         = 'SMC_0201R'                | '(SMC_0201R_C)'                                 | 'CAP,220PF,5%,50V,C0G,0201'                                                       | ''        
 'G104-0B332-EK'  | '3300PF'  | '10%'        = 'SMC_0201R'                | '(SMC_0201R_C)'                                 | 'CAP,3300PF,10%,25V,X7R,0201'                                                     | ''        
 'G105-0B271-FJ'  | '270PF'   | '5%'         = 'SMC_0402R_H022'           | '(SMC_0402R_C_H022)'                            | 'CAP,270PF,5%,50V,X7R,0402'                                                       | ''        
 'G107-0C106-BK'  | '10UF'    | '10%'        = 'SMC_0805R_H057'           | '(SMC_0805R_H057)'                              | 'CAP,10UF,10%,6.3V,X5R,CER,0805'                                                  | 'NFND'    
 'A101-00005-JN'  | '4.7UF'   | '20%'        = 'SMC_0402R_H026'           | '(SMC_0402R_C_H026)'                            | 'CAP,4.7UF,20%,6.3V,X6S,CER,0402'                                                 | ''        
 'G104-0A220-FJ'  | '22PF'    | '5%'         = 'SMC_0201R'                | '(SMC_0201R_C)'                                 | 'CAP, 22PF, +/-5%, 50V, C0G, 0201'                                                | ''        
 'G105-0F106-BM'  | '10UF'    | '20%'        = 'SMC_0402R_H028'           | '(SMC_0402R_C_H028,C0402_BGA)'                  | 'CAP,10UF,20%,6.3V,X6S,0402'                                                      | 'NFND'    
 'G107-0F106-EM'  | '10UF'    | '20%'        = 'SMC_0805R_H057'           | '(SMC_0805R_H057)'                              | 'CAP,10UF,20%,25V,X6S,0805'                                                       | ''        
 'G106-0B684-CK'  | '0.68UF'  | '10%'        = 'SMC_0603R_H035'           | '(SMC_0603R_H035)'                              | 'CAP,0.68UF,10%,10V,X7R,0603'                                                     | ''        
 'A101-00015-HT'  | '0.1UF'   | '10%'        = 'SMC_0402R_H022'           | '(SMC_0402R_C_H022)'                            | 'CAP,0.1UF,10%,16V,X5R,0402'                                                      | ''        
 'G101-10107-01'  | '47UF'    | '20%'        = 'SMC_0805R_H057'           | '(SMC_0805R_H057)'                              | 'CAP,47UF, 20%,4V, X6S, 0805 '                                                    | 'REJECTED'
 'G101-10106-01'  | '22UF'    | '20%'        = 'SMC_0603R_H039'           | '(SMC_0603R_H039)'                              | 'CAP, 22UF, 20%,4V, X6S, 0603'                                                    | 'REJECTED'
 'G101-10105-01'  | '10UF'    | '20%'        = 'SMC_0603R_H035'           | '(SMC_0603R_H035)'                              | 'CAP, 10UF, 20%,4V, X6S, 0603'                                                    | 'REJECTED'
 'G101-10104-01'  | '1UF'     | '20%'        = 'SMC_0201R'                | '(SMC_0201R_C)'                                 | 'CAP, 1UF, 20%,4V, X6S, 0201'                                                     | 'REJECTED'
 'G101-10103-01'  | '1UF'     | '20%'        = 'SMC_0201R'                | '(SMC_0201R_C)'                                 | 'CAP, 1UF, 20%, 6.3V, X6S, 0201'                                                  | 'REJECTED'
 'G101-10102-01'  | '10UF'    | '20%'        = 'SMC_0603R_H039'           | '(SMC_0603R_H039)'                              | 'CAP, 10UF, 20%, 10V, X6S, 0603'                                                  | 'REJECTED'
 'G101-10101-01'  | '1UF'     | '20%'        = 'SMC_0201R'                | '(SMC_0201R_C)'                                 | 'CAP, 1UF, 20%, 10V, X6S, 0201'                                                   | 'REJECTED'
 'G101-10100-01'  | '4.7UF'   | '20%'        = 'SMC_0603R_H039'           | '(SMC_0603R_H039)'                              | 'CAP, 4.7UF, 20%, DC25V, X6S, 0603'                                               | 'REJECTED'
 'G104-0F104-EM'  | '0.1UF'   | '20%'        = 'SMC_0201R'                | '(SMC_0201R_C)'                                 | 'CAP,0.1UF,20%,25V,X6S,0201'                                                      | ''        
 'G104-0F104-CM'  | '0.1UF'   | '20%'        = 'SMC_0201R'                | '(SMC_0201R_C)'                                 | 'CAP,0.1UF,20%,10V,X6S,0201'                                                      | ''        
 'G104-0F104-BM'  | '0.1UF'   | '20%'        = 'SMC_0201R'                | '(SMC_0201R_C)'                                 | 'CAP,0.1UF,20%,6.3V,X6S,0201'                                                     | ''        
 'G104-0B101-DK'  | '100PF'   | '10%'        = 'SMC_0201R'                | '(SMC_0201R_C)'                                 | 'CAP,100PF,10%,16V,X7R,0201'                                                      | ''        
 'G104-0B332-BK'  | '3300PF'  | '10%'        = 'SMC_0201R'                | '(SMC_0201R_C)'                                 | 'CAP,3300PF,10%,6.3V,X7R,0201'                                                    | ''        
 'G104-0F333-BK'  | '0.033UF' | '10%'        = 'SMC_0201R'                | '(SMC_0201R_C)'                                 | 'CAP,0.033UF,10%,6.3V,X6S,0201'                                                   | ''        
 'G104-0F683-BM'  | '0.068UF' | '20%'        = 'SMC_0201R'                | '(SMC_0201R_C)'                                 | 'CAP,0.068UF,20%,6.3V,X6S,0201'                                                   | ''        
 'G104-0F104-BK'  | '0.1UF'   | '10%'        = 'SMC_0201R'                | '(SMC_0201R_C)'                                 | 'CAP,0.1UF,10%,6.3V,X6S,0201'                                                     | ''        
 'G104-0B103-BK'  | '0.01UF'  | '10%'        = 'SMC_0201R'                | '(SMC_0201R_C)'                                 | 'CAP,0.01UF,10%,6.3V,X7R,0201'                                                    | ''        
 'G105-0B104-BK'  | '0.1UF'   | '10%'        = 'SMC_0402R_H022'           | '(SMC_0402R_C_H022)'                            | 'CAP,0.1UF,10%,6.3V,X7R,0402'                                                     | ''        
 'G105-0F105-CK'  | '1UF'     | '10%'        = 'SMC_0402R_H022'           | '(SMC_0402R_C_H022,C0402_BGA,C0402-0P8MM-45DG,C0402-P8MM-S0,C0402-1MM-TRIANGLE-S0)' | 'CAP,1UF,10%,10V,X6S,0402'                                                        | ''        
 'G105-0B224-BK'  | '0.22UF'  | '10%'        = 'SMC_0402R_H022'           | '(SMC_0402R_C_H022)'                            | 'CAP,0.22UF,10%,6.3V,X7R,0402'                                                    | ''        
 'G104-0B682-BK'  | '6800PF'  | '10%'        = 'SMC_0201R'                | '(SMC_0201R_C)'                                 | 'CAP,6800PF,10%,6.3V,X7R,0201'                                                    | ''        
 'G107-0F476-AM'  | '47UF'    | '20%'        = 'SMC_0805R_H057'           | '(SMC_0805R_H057)'                              | 'CAP,47UF,20%,4V,X6S,0805'                                                        | ''        
 'G107-0F226-AM'  | '22UF'    | '20%'        = 'SMC_0805R_H055'           | '(SMC_0805R_H055)'                              | 'CAP,22UF,20%,4V,X6S,0805'                                                        | ''        
 'G106-0F106-AM'  | '10UF'    | '20%'        = 'SMC_0603R_H037'           | '(SMC_0603R_H037)'                              | 'CAP,10UF,20%,4V,X6S,0603'                                                        | ''        
 'G105-0B224-CK'  | '0.22UF'  | '10%'        = 'SMC_0402R_H022'           | '(SMC_0402R_C_H022,C0402-1MM-TRIANGLE-S0,C0402-P8MM-S0)'                            | 'CAP,0.22UF,10%,10V,X7R,0402'                                                     | ''        
 'G105-0F105-AM'  | '1UF'     | '20%'        = 'SMC_0402R_H014'           | '(SMC_0402R_C_H014,C0402_BGA)'                  | 'CAP,1UF,20%,4V,X6S,0402'                                                         | ''        
 'G106-0F475-EK'  | '4.7UF'   | '10%'        = 'SMC_0603R_H039'           | '(SMC_0603R_H039)'                              | 'CAP,4.7UF,10%,25V,X6S,0603'                                                      | ''        
 'G108-0F226-EK'  | '22UF'    | '10%'        = 'SMC_1206R_H075'           | '(SMC_1206R_H075)'                              | 'CAP,22UF,10%,25V,X6S,1206'                                                       | ''        
 'G108-0B226-CM'  | '22UF'    | '20%'        = 'SMC_1206R_H071'           | '(SMC_1206R_H071)'                              | 'CAP,22UF,20%,10V,X7R,1206'                                                       | ''        
 'G106-0F106-CM'  | '10UF'    | '20%'        = 'SMC_0603R_H039'           | '(SMC_0603R_H039)'                              | 'CAP,10UF,20%,10V,X6S,0603'                                                       | ''        
 'G105-0B104-CK'  | '0.1UF'   | '10%'        = 'SMC_0402R_H022'           | '(SMC_0402R_C_H022,C0402_BGA,C0402-0P8MM-45DG,C0402-1MM-TRIANGLE-S0)' | 'CAP,0.1UF,10%,10V,X7R,0402'                                                      | ''        
 'G106-0F226-AM'  | '22UF'    | '20%'        = 'SMC_0603R_H039'           | '(SMC_0603R_H039)'                              | 'CAP,22UF,20%,4V,X6S,0603'                                                        | ''        
 'G107-0F226-CM'  | '22UF'    | '20%'        = 'SMC_0805R_H057'           | '(SMC_0805R_H057)'                              | 'CAP,22UF,20%,10V,X6S,0805'                                                       | ''        
 'A101-10017-HT'  | '10UF'    | '10%'        = 'SMC_0603R_H039'           | '(SMC_0603R_H039)'                              | 'CAP, 10U, 10%, X5R, 10V, 0603'                                                   | ''        
 'A101-10016-HT'  | '2.2UF'   | '10%'        = 'SMC_0402R_H022'           | '(SMC_0402R_C_H022)'                            | 'CAP, 2.2U, 10%, X5R, 6.3V, 0402'                                                 | ''        
 'A101-00025-HT'  | '22PF'    | '5%'         = 'SMC_0402R_H022'           | '(SMC_0402R_C_H022)'                            | 'CAP, 22PF, +/-5%, 50V, C0G, 0402'                                                | ''        
 'A105-0A221-HT'  | '220PF'   | '5%'         = 'SMC_0402R_H022'           | '(SMC_0402R_C_H022)'                            | 'CAP,220PF,5%,50V,C0G,0402'                                                       | ''        
 'A105-0A101-HT'  | '100PF'   | '5%'         = 'SMC_0402R_H022'           | '(SMC_0402R_C_H022)'                            | 'CAP,100PF,5%,50V,C0G,0402'                                                       | ''        
 'A105-0A100-HT'  | '10PF'    | '5%'         = 'SMC_0402R_H022'           | '(SMC_0402R_C_H022)'                            | 'CAP,10PF,+/-0.5PF,50V,C0G,0402'                                                  | ''        
 'A104-0C224-HT'  | '0.22UF'  | '10%'        = 'SMC_0201R'                | '(SMC_0201R_C)'                                 | 'CAP,0.22UF,10%,6.3V,X5R,0201'                                                    | ''        
 'A104-0C105-HT'  | '1UF'     | '20%'        = 'SMC_0201R'                | '(SMC_0201R_C)'                                 | 'CAP,1UF,20%,6.3V,X5R,0201'                                                       | ''        
 'A105-0B102-HT'  | '1000PF'  | '10%'        = 'SMC_0402R_H022'           | '(SMC_0402R_C_H022)'                            | 'CAP,1000PF,10%,50V,X7R,0402'                                                     | ''        
 'A105-0B103-HT'  | '0.01UF'  | '10%'        = 'SMC_0402R_H022'           | '(SMC_0402R_C_H022)'                            | 'CAP,0.01UF,10%,25V,X7R,CER,0402'                                                 | ''        
 'A105-0C224-HT'  | '0.22UF'  | '10%'        = 'SMC_0402R_H022'           | '(SMC_0402R_C_H022)'                            | 'CAP,0.22UF,10%,16V,X5R,0402'                                                     | ''        
 'A105-0C106-HT'  | '10UF'    | '20%'        = 'SMC_0402R_H028'           | '(SMC_0402R_C_H028)'                            | 'CAP,10UF,20%,6.3V,X5R,0402'                                                      | ''        
 'A105-0C105-HT'  | '1.0UF'   | '10%'        = 'SMC_0402R_H028'           | '(SMC_0402R_C_H028)'                            | 'CAP,1.0UF,10%,6.3V,X5R,0402'                                                     | ''        
 'G104-0F105-BM'  | '1UF'     | '20%'        = 'SMC_0201R_H015'           | '(SMC_0201R_C_H015,C0201-GLASS-S0)'             | 'CAP,1UF,20%,6.3V,X6S,0201'                                                       | ''        
 'A105-0C104-HT'  | '0.1UF'   | '10%'        = 'SMC_0402R_H022'           | '(SMC_0402R_C_H022)'                            | 'CAP,0.1UF,10%,10V,X5R,CER,0402'                                                  | ''        
 'A105-AA105-HT'  | '1UF'     | '10%'        = 'SMC_0402R_H022'           | '(SMC_0402R_C_H022)'                            | 'CAP,1UF,10%,10V,X5R,0402'                                                        | ''        
 'A105-0B332-HT'  | '3300PF'  | '10%'        = 'SMC_0402R_H022'           | '(SMC_0402R_C_H022)'                            | 'CAP,3300PF,10%,25V,X7R,0402'                                                     | ''        
 'A105-0B223-HT'  | '0.022UF' | '10%'        = 'SMC_0402R_H022'           | '(SMC_0402R_C_H022)'                            | 'CAP,0.022UF,10%,16V,X7R,CER,0402'                                                | ''        
 'A105-0B222-HT'  | '2200PF'  | '10%'        = 'SMC_0402R_H022'           | '(SMC_0402R_C_H022)'                            | 'CAP,2200PF,10%,25V,X7R ,SMD 0402'                                                | ''        
 'A106-0B105-HT'  | '1UF'     | '10%'        = 'SMC_0603R_H037'           | '(SMC_0603R_H037)'                              | 'CAP,1UF,10%,16V,X7R,CER,0603'                                                    | ''        
 'A106-0B225-HT'  | '2.2UF'   | '10%'        = 'SMC_0603R_H035'           | '(SMC_0603R_H035)'                              | 'CAP,2.2UF, 10%,10V,X7R,0603'                                                     | ''        
 'A106-0C225-HT'  | '2.2UF'   | '10%'        = 'SMC_0603R_H035'           | '(SMC_0603R_H035)'                              | 'CAP,2.2UF, 10%,X5R,16V,0603'                                                     | ''        
 'A106-0C226-HT'  | '22UF'    | '20%'        = 'SMC_0603R_H039'           | '(SMC_0603R_H039)'                              | 'CAP,22U,20%,6.3V,X5R,0603'                                                       | ''        
 'A106-0C106-HT'  | '10UF'    | '20%'        = 'SMC_0603R_H037'           | '(SMC_0603R_H037)'                              | 'CAP,10UF,20%,6.3V,X5R,0603'                                                      | ''        
 'A101-10091-HT'  | '2.2UF'   | '20%'        = 'SMC_0402R_H022'           | '(SMC_0402R_C_H022)'                            | 'CAP, 2.2UF, 20%, X6S, 6.3V, 0402'                                                | ''        
 'A107-AA226-HT'  | '22UF'    | '20%'        = 'SMC_0805R_H057'           | '(SMC_0805R_H057)'                              | 'CAP,22UF,20%,16V,X5R,0805'                                                       | ''        
 'A101-00009-HT'  | '10UF'    | '10%'        = 'SMC_1206R_H071'           | '(SMC_1206R_H071)'                              | 'CAP,10UF,10%,25V,X5R,1206'                                                       | ''        
 'A107-0B106-HT'  | '10UF'    | '20%'        = 'SMC_0805R_H057'           | '(SMC_0805R_H057)'                              | 'CAP,10UF,20%,16V,X7R,0805'                                                       | ''        
 'A109-0C476-HT'  | '47UF'    | '10%'        = 'SMC_1210R_H106'           | '(SMC_1210R_H106)'                              | 'CAP,47UF,10%,16V,X5R,1210'                                                       | ''        
 'A109-0C107-HT'  | '100UF'   | '20%'        = 'SMC_1210R_H106'           | '(SMC_1210R_H106)'                              | 'CAP,100UF,20%,6.3V,X5R,CER,1210'                                                 | ''        
 'A107-0C226-HT'  | '22UF'    | '20%'        = 'SMC_0805R_H057'           | '(SMC_0805R_H057)'                              | 'CAP,22UF,20%,6.3V,X5R,CER,0805'                                                  | ''        
 'A107-0C476-HT'  | '47UF'    | '20%'        = 'SMC_0805R_H057'           | '(SMC_0805R_H057)'                              | 'CAP,47UF,20%,6.3V,X5R,CER,0805'                                                  | ''        
 'A105-0B104-HT'  | '0.1UF'   | '10%'        = 'SMC_0402R'                | '(SMC_0402R_C)'                                 | 'CAP,0.1UF,10%,16V,X7R,CER,0402'                                                  | ''        
 'A105-AA103-HT'  | '0.01UF'  | '10%'        = 'SMC_0402R_H022'           | '(SMC_0402R_C_H022)'                            | 'CAP,0.01UF,10%,50V,X7R,0402'                                                     | ''        
 'A105-0A330-HT'  | '33PF'    | '5%'         = 'SMC_0402R_H022'           | '(SMC_0402R_C_H022)'                            | 'CAP,33PF,5%,50V,C0G,0402'                                                        | ''        
 'A105-0A471-HT'  | '470PF'   | '5%'         = 'SMC_0402R_H022'           | '(SMC_0402R_C_H022)'                            | 'CAP,470PF,5%,50V,C0G,0402'                                                       | ''        
 'A105-0A270-HT'  | '27PF'    | '5%'         = 'SMC_0402R_H022'           | '(SMC_0402R_C_H022)'                            | 'CAP,27PF,5%,50V,C0G,0402'                                                        | ''        
 'A101-10018-HT'  | '4.7UF'   | '20%'        = 'SMC_0402R_H026'           | '(SMC_0402R_C_H026)'                            | 'CAP, 4.7U, 20%, X5R, 6.3V, 0402'                                                 | ''        
 'A104-0C104-HT'  | '0.1UF'   | '10%'        = 'SMC_0201R'                | '(SMC_0201R_C)'                                 | 'CAP,0.1UF,10%,6.3V,X5R,CER,0201'                                                 | ''        
 'A105-AA104-HT'  | '0.1UF'   | '10%'        = 'SMC_0402R_H022'           | '(SMC_0402R_C_H022)'                            | 'CAP,0.1UF,10%,50V,X7R,CER,0402'                                                  | ''        
 'A105-0C473-HT'  | '0.047UF' | '10%'        = 'SMC_0402R_H022'           | '(SMC_0402R_C_H022)'                            | 'CAP,0.047UF,10%,16V,X5R,CER,0402'                                                | ''        
 'A105-0C824-HT'  | '0.082UF' | '10%'        = 'SMC_0402R_H022'           | '(SMC_0402R_C_H022)'                            | 'CAP,0.82UF,10%,X5R,10V,0402'                                                     | ''        
 'A105-0B474-HT'  | '0.47UF'  | '10%'        = 'SMC_0402R_H022'           | '(SMC_0402R_C_H022)'                            | 'CAP,0.47UF,10%,10V,X7R,0402'                                                     | ''        
 'A105-0A180-HT'  | '18PF'    | '5%'         = 'SMC_0402R_H022'           | '(SMC_0402R_C_H022)'                            | 'CAP, 18PF,+/-5%, 50V, C0G, 0402'                                                 | ''        
 'A105-0A220-HT'  | '22PF'    | '5%'         = 'SMC_0402R_H022'           | '(SMC_0402R_C_H022)'                            | 'CAP,22PF,5%,50V,C0G,0402'                                                        | ''        
 'A106-0B104-HT'  | '0.1UF'   | '20%'        = 'SMC_0603R_H035'           | '(SMC_0603R_H035)'                              | 'CAP,0.1UF,20%,25V,X7R,0603'                                                      | ''        
 'A107-0C106-HT'  | '10UF'    | '10%'        = 'SMC_0805R_H057'           | '(SMC_0805R_H057)'                              | 'CAP,10UF,10%,25V,X5R,0805'                                                       | ''        
 'A105-0B393-HT'  | '39NF'    | '10%'        = 'SMC_0402R_H022'           | '(SMC_0402R_C_H022)'                            | 'CAP,39NF,10%,16V,X7R,0402'                                                       | ''        
 'A101-00016-TS'  | '15PF'    | '5%'         = 'SMC_0402R_H022'           | '(SMC_0402R_C_H022)'                            | 'CAP, 15PF, +/-5%, 50V, C0G, 0402'                                                | ''        
 'A101-00015-TS'  | '0.1UF'   | '10%'        = 'SMC_0402R_H022'           | '(SMC_0402R_C_H022)'                            | 'CAP,0.1UF,10%,16V,X5R,0402'                                                      | ''        
 'A105-0A101-TS'  | '100PF'   | '5%'         = 'SMC_0402R_H022'           | '(SMC_0402R_C_H022)'                            | 'CAP,100PF,5%,50V,C0G,0402'                                                       | ''        
 'G104-0A120-FJ'  | '12PF'    | '5%'         = 'SMC_0201R'                | '(SMC_0201R_C)'                                 | 'CAP,12PF,5%,50V,C0G,0201'                                                        | ''        
 'G104-0A180-FJ'  | '18PF'    | '5%'         = 'SMC_0201R'                | '(SMC_0201R_C)'                                 | 'CAP,18PF,5%,50V,C0G,0201'                                                        | ''        
 'G104-0A330-FJ'  | '33PF'    | '5%'         = 'SMC_0201R'                | '(SMC_0201R_C)'                                 | 'CAP,33PF,5%,50V,C0G,0201'                                                        | ''        
 '210-052992'     | '2.2UF'   | '10%'        = 'SMC_0402R_H028'           | '(SMC_0402R_C_H028)'                            | 'CAP, 0402, 2.2UF, X5R, 10%, 16V, CER'                                            | ''        
 '210-074682'     | '0.1UF'   | '10%'        = 'SMC_0201R_H015'           | '(SMC_0201R_C_H015)'                            | 'CAP,0.1UF,10%,16V,X6S,0201'                                                      | ''        
 'A105-0A100-TS'  | '10PF'    | '5%'         = 'SMC_0402R_H022'           | '(SMC_0402R_C_H022)'                            | 'CAP,10PF,+/-0.5PF,50V,C0G,0402'                                                  | 'NFND'        
 'A105-0B224-TS'  | '0.22UF'  | '10%'        = 'SMC_0402R_H022'           | '(SMC_0402R_C_H022)'                            | 'CAP,0.22UF,10%,X7R,16V,0402'                                                     | ''        
 'A101-10036-TS'  | '22UF'    | '20%'        = 'SMC_0805R_H055'           | '(SMC_0805R_H055)'                              | 'CAP,22UF,X6S,4V,20%,0805'                                                        | ''        
 'A101-00018-TS'  | '4.7UF'   | '10%'        = 'SMC_0603R_H037'           | '(SMC_0603R_H037)'                              | 'CAP, 4.7UF, +/-10%, 6.3V, X5R, 0603'                                             | ''        
 'A101-10020-TS'  | '15NF'    | '10%'        = 'SMC_0402R_H022'           | '(SMC_0402R_C_H022)'                            | 'CAP,15NF,10%,16V,X7R,0402'                                                       | ''        
 'A101-00020-TS'  | '1UF'     | '10%'        = 'SMC_0402R_H022'           | '(SMC_0402R_C_H022)'                            | 'CAP, 1UF, +/-10%, 10V, X5R, 0402'                                                | ''        
 'A101-10078-TS'  | '100UF'   | '20%'        = 'SMC_0805R_H057'           | '(SMC_0805R_H057)'                              | 'CAP,100UF,20%,2.5V,X5R,CER,0805'                                                 | ''        
 'A107-0C226-JN'  | '22UF'    | '20%'        = 'SMC_0805R_H055'           | '(SMC_0805R_H055)'                              | 'CAP,22UF,20%,10V,X5R,0805'                                                       | ''        
 '210-069809'     | '10UF'    | '10%'        = 'SMC_0805R_H057'           | '(SMC_0805R_H057)'                              | 'CAP,10UF,10%,25V,X5R,0805'                                                       | ''        
 'G108-0F476-BM'  | '47UF'    | '20%'        = 'SMC_1206R_H071'           | '(SMC_1206R_H071)'                              | 'CAP,47UF, 20%,6.3V,X6S,-55-105C,1206'                                            | ''        
 'A105-0C105-TS'  | '1UF'     | '10%'        = 'SMC_0402R_H022'           | '(SMC_0402R_C_H022)'                            | 'CAP,1UF,10%,10V,X5R,0402'                                                        | ''        
 'A105-0C104-TS'  | '0.1UF'   | '10%'        = 'SMC_0402R_H022'           | '(SMC_0402R_C_H022)'                            | 'CAP,0.1UF,10%,10V,X5R,CER,0402'                                                  | ''        
 'A105-0B474-TS'  | '0.47UF'  | '10%'        = 'SMC_0402R_H022'           | '(SMC_0402R_C_H022)'                            | 'CAP,0.47UF,10%,10V,X7R,0402'                                                     | ''        
 'A105-0B103-TS'  | '0.01UF'  | '10%'        = 'SMC_0402R_H022'           | '(SMC_0402R_C_H022)'                            | 'CAP,0.01UF,10%,16V,X7R,0402'                                                     | ''        
 'A105-AA103-TS'  | '0.01UF'  | '10%'        = 'SMC_0402R_H022'           | '(SMC_0402R_C_H022)'                            | 'CAP,0.01UF,10%,25V,X7R,CER,0402'                                                 | ''        
 'A105-0B222-TS'  | '2200PF'  | '10%'        = 'SMC_0402R_H022'           | '(SMC_0402R_C_H022)'                            | 'CAP,2200PF,10%,25V,X7R ,0402'                                                    | ''        
 'A105-0B104-TS'  | '0.1UF'   | '10%'        = 'SMC_0402R_H022'           | '(SMC_0402R_C_H022)'                            | 'CAP,0.1UF,10%,16V,X7R,CER,0402'                                                  | ''        
 'A105-AA104-TS'  | '0.1UF'   | '10%'        = 'SMC_0402R_H022'           | '(SMC_0402R_C_H022)'                            | 'CAP,0.1UF,10%,25V,X7R,CER,0402'                                                  | ''        
 'A105-BB104-TS'  | '0.1UF'   | '10%'        = 'SMC_0402R_H022'           | '(SMC_0402R_C_H022)'                            | 'CAP,0.1UF,10%,50V,X7R,CER,0402'                                                  | ''        
 'A105-AA222-TS'  | '2200PF'  | '10%'        = 'SMC_0402R_H022'           | '(SMC_0402R_C_H022)'                            | 'CAP,2200PF,10%,X7R,50V,0402'                                                     | ''        
 'A105-0C106-TS'  | '10UF'    | '20%'        = 'SMC_0402R_H028'           | '(SMC_0402R_C_H028)'                            | 'CAP,10UF,20%,6.3V,X5R,0402'                                                      | ''        
 'A106-0B105-TS'  | '1UF'     | '10%'        = 'SMC_0603R_H037'           | '(SMC_0603R_H037)'                              | 'CAP,1UF,10%,16V,X7R,CER,0603'                                                    | ''        
 'A106-0C105-TS'  | '1UF'     | '10%'        = 'SMC_0603R_H035'           | '(SMC_0603R_H035)'                              | 'CAP,1UF,10%,25V,X5R,CER,0603'                                                    | ''        
 'A106-0C106-TS'  | '10UF'    | '20%'        = 'SMC_0603R_H037'           | '(SMC_0603R_H037)'                              | 'CAP,10UF,20%,6.3V,X5R,0603'                                                      | ''        
 'A107-0B106-TS'  | '10UF'    | '20%'        = 'SMC_0805R_H057'           | '(SMC_0805R_H057)'                              | 'CAP,10UF,20%,16V,X7R,0805'                                                       | ''        
 'A107-0C226-TS'  | '22UF'    | '20%'        = 'SMC_0805R_H057'           | '(SMC_0805R_H057)'                              | 'CAP,22UF,20%,6.3V,X5R,CER,0805'                                                  | ''        
 'A108-0C226-TS'  | '22UF'    | '20%'        = 'SMC_1206R_H075'           | '(SMC_1206R_H075)'                              | 'CAP,22UF,20%,25V,X5R,1206'                                                       | ''        
 'A108-0C476-TS'  | '47UF'    | '20%'        = 'SMC_1206R_H075'           | '(SMC_1206R_H075)'                              | 'CAP,47U,20%,X5R,10V,1206'                                                        | ''        
 'A109-0C476-TS'  | '47UF'    | '10%'        = 'SMC_1210R_H110'           | '(SMC_1210R_H110)'                              | 'CAP,47UF,10%,16V,X5R,1210'                                                       | ''        
 'A108-AA476-TS'  | '47UF'    | '20%'        = 'SMC_1206R_H071'           | '(SMC_1206R_H071)'                              | 'CAP, 47UF, 20%, 25V, X5R, 1206'                                                  | ''        
 'G104-0B101-FM'  | '100PF'   | '20%'        = 'SMC_0201R'                | '(SMC_0201R_C)'                                 | 'CAP,100PF,20%,50V,X7R,0201'                                                      | ''        
 'G104-0B682-EK'  | '6800PF'  | '10%'        = 'SMC_0201R'                | '(SMC_0201R_C)'                                 | 'CAP,6800PF,10%,25V,X7R,0201'                                                     | ''        
 'G104-0B332-EM'  | '3300PF'  | '20%'        = 'SMC_0201R'                | '(SMC_0201R_C)'                                 | 'CAP,3300PF,20%,25V,X7R,0201'                                                     | ''        
 'G104-0B331-FM'  | '330PF'   | '20%'        = 'SMC_0201R'                | '(SMC_0201R_C)'                                 | 'CAP,330PF,20%,50V,X7R,0201'                                                      | ''        
 'G104-0B102-FM'  | '1000PF'  | '20%'        = 'SMC_0201R'                | '(SMC_0201R_C)'                                 | 'CAP,1000PF,20%,50V,X7R,0201'                                                     | ''        
 'G105-0B222-FM'  | '2200PF'  | '20%'        = 'SMC_0402R_H022'           | '(SMC_0402R_C_H022)'                            | 'CAP,2200PF,20%,50V,X7R,0402'                                                     | ''        
 'G105-0F224-EM'  | '0.22UF'  | '20%'        = 'SMC_0402R_H022'           | '(SMC_0402R_C_H022)'                            | 'CAP,0.22UF,20%,25V,X6S,0402'                                                     | ''        
 'G104-0B103-EK'  | '0.01UF'  | '10%'        = 'SMC_0201R'                | '(SMC_0201R_C)'                                 | 'CAP,0.01UF,10%,25V,X7R,0201'                                                     | ''        
 'G104-0F224-BM'  | '0.22UF'  | '20%'        = 'SMC_0201R'                | '(SMC_0201R_C)'                                 | 'CAP,0.22UF,20%,6.3V,X6S,0201'                                                    | ''        
 'G104-0F474-AM'  | '0.47UF'  | '20%'        = 'SMC_0201R'                | '(SMC_0201R_C)'                                 | 'CAP,0.47UF,20%,4V,X6S,0201'                                                      | ''        
 'G105-0F475-BM'  | '4.7UF'   | '20%'        = 'SMC_0402R_H026'           | '(SMC_0402R_C_H026,C0402_BGA,C0402-0P8MM-45DG,C0402-1MM-TRIANGLE-S0)' | 'CAP,4.7UF,20%,6.3V,X6S,0402'                                                     | ''        
 'G105-0F225-BM'  | '2.2UF'   | '20%'        = 'SMC_0402R_H022'           | '(SMC_0402R_C_H022)'                            | 'CAP,2.2UF,20%,6.3V,X6S,0402'                                                     | ''        
 'G107-0B473-GK'  | '0.047UF' | '10%'        = 'SMC_0805R_H057'           | '(SMC_0805R_H057)'                              | 'CAP, 0.047UF, +/-10%,100V,X7R,CER,0805'                                          | ''        
 'G101-10108-01'  | '1000PF'  | '10%'        = 'SMC_1808R_H087'           | '(SMC_1808R_H087)'                              | 'CAP,1000PF,10%,3KV,X7R,1808'                                                     | ''        
 'G104-0F224-BK'  | '0.22UF'  | '10%'        = 'SMC_0201R'                | '(SMC_0201R_C)'                                 | 'CAP,0.22UF,10%,6.3V,X6S,0201'                                                    | ''        
 'G104-0B101-FK'  | '100PF'   | '10%'        = 'SMC_0201R'                | '(SMC_0201R_C)'                                 | 'CAP,100PF,10%,50V,X7R,0201'                                                      | ''        
 'G104-0B331-FK'  | '330PF'   | '10%'        = 'SMC_0201R'                | '(SMC_0201R_C)'                                 | 'CAP,330PF,10%,50V,X7R,0201'                                                      | ''        
 'A106-0B154-HT'  | '0.15UF'  | '10%'        = 'SMC_0603R_H035'           | '(SMC_0603R_H035)'                              | 'CAP,0.15UF,10%,25V,X7R,0603'                                                     | ''        
 'A105-0A120-HT'  | '12PF'    | '5%'         = 'SMC_0402R_H022'           | '(SMC_0402R_C_H022)'                            | 'CAP,12PF,5%,50V,C0G,CER,0402'                                                    | ''        
 'G105-0B474-BK'  | '0.47UF'  | '10%'        = 'SMC_0402R_H022'           | '(SMC_0402R_C_H022)'                            | 'CAP,0.47UF,10%,6.3V,X7R,0402'                                                    | ''        
 'G105-0F225-CM'  | '2.2UF'   | '20%'        = 'SMC_0402R_H024'           | '(SMC_0402R_C_H024,C0402_BGA,C0402-0P8MM-45DG)' | 'CAP,2.2UF,20%,10V,X6S,0402'                                                      | ''        
 'A104-BG220-HT'  | '22PF'    | '5%'         = 'SMC_0201R'                | '(SMC_0201R_C)'                                 | 'CAP,22PF,5%,50V,C0G,0201'                                                        | ''        
 'A104-BG180-HT'  | '18PF'    | '5%'         = 'SMC_0201R'                | '(SMC_0201R_C)'                                 | 'CAP,18PF,5%,50V,C0G,0201'                                                        | ''        
 'A104-BG270-HT'  | '27PF'    | '5%'         = 'SMC_0201R'                | '(SMC_0201R_C)'                                 | 'CAP,27PF,5%,50V,C0G,0201'                                                        | ''        
 'A104-BG330-HT'  | '33PF'    | '5%'         = 'SMC_0201R'                | '(SMC_0201R_C)'                                 | 'CAP,33PF,5%,50V,C0G,0201'                                                        | ''        
 'A104-DC103-HT'  | '0.01UF'  | '10%'        = 'SMC_0201R'                | '(SMC_0201R_C)'                                 | 'CAP,0.01UF,10%,25V,X7R,0201'                                                     | ''        
 'A105-CN104-HT'  | '0.1UF'   | '10%'        = 'SMC_0402R_H022'           | '(SMC_0402R_C_H022)'                            | 'CAP,0.1UF,10%,10V,X7R,0402'                                                      | ''        
 'A104-DH101-HT'  | '100PF'   | '10%'        = 'SMC_0201R'                | '(SMC_0201R_C)'                                 | 'CAP,100PF,10%,50V,X7R,0201'                                                      | ''        
 'A104-KI224-HT'  | '0.22UF'  | '10%'        = 'SMC_0201R'                | '(SMC_0201R_C)'                                 | 'CAP,0.22UF,10%6.3V,X6S,0201'                                                     | ''        
 'A104-DH102-HT'  | '1000PF'  | '10%'        = 'SMC_0201R'                | '(SMC_0201R_C)'                                 | 'CAP,1000PF,10%,50V,X7R,0201'                                                     | ''        
 'A104-LD104-HT'  | '0.1UF'   | '20%'        = 'SMC_0201R'                | '(SMC_0201R_C)'                                 | 'CAP,0.1UF,20%,25V,X6S,0201'                                                      | ''        
 'A105-DH222-HT'  | '2200PF'  | '10%'        = 'SMC_0402R_H022'           | '(SMC_0402R_C_H022)'                            | 'CAP,2200PF,10%,50V,X7R,0402'                                                     | ''        
 'A106-LC475-HT'  | '4.7UF'   | '10%'        = 'SMC_0603R_H039'           | '(SMC_0603R_H039)'                              | 'CAP,4.7UF,10%,25V,X6S,0603'                                                      | ''        
 'A107-LD106-HT'  | '10UF'    | '20%'        = 'SMC_0805R_H057'           | '(SMC_0805R_H057)'                              | 'CAP,10UF,20%,25V,X6S,0805'                                                       | ''        
 'A108-LC226-HT'  | '22UF'    | '10%'        = 'SMC_1206R_H075'           | '(SMC_1206R_H075)'                              | 'CAP,22UF,10%,25V,X6S,1206'                                                       | ''        
 'A104-KO104-HT'  | '0.1UF'   | '20%'        = 'SMC_0201R'                | '(SMC_0201R_C)'                                 | 'CAP,0.1UF,20%,10V,X6S,0201'                                                      | ''        
 'A104-KN105-HT'  | '1UF'     | '10%'        = 'SMC_0402R_H022'           | '(SMC_0402R_C_H022)'                            | 'CAP,1UF,10%,10V,X6S,0402'                                                        | ''        
 'A106-KO106-HT'  | '10UF'    | '20%'        = 'SMC_0603R_H039'           | '(SMC_0603R_H039)'                              | 'CAP,10UF,20%,10V,X6S,0603'                                                       | ''        
 'A107-KO226-HT'  | '22UF'    | '20%'        = 'SMC_0805R_H057'           | '(SMC_0805R_H057)'                              | 'CAP,22UF,20%,10V,X6S,0805'                                                       | ''        
 'A104-KI104-HT'  | '0.1UF'   | '10%'        = 'SMC_0201R'                | '(SMC_0201R_C)'                                 | 'CAP,0.1UF,10%,6.3V,X6S,0201'                                                     | ''        
 'A104-KJ105-HT'  | '1UF'     | '20%'        = 'SMC_0201R_H015'           | '(SMC_0201R_C_H015)'                            | 'CAP,1UF,20%,6.3V,X6S,0201'                                                       | ''        
 'A104-DH331-HT'  | '330PF'   | '10%'        = 'SMC_0201R'                | '(SMC_0201R_C)'                                 | 'CAP,330PF,10%,50V,X7R,0201'                                                      | ''        
 'A104-BG120-HT'  | '12PF'    | '5%'         = 'SMC_0201R'                | '(SMC_0201R_C)'                                 | 'CAP,12PF,5%,50V,C0G,0201'                                                        | ''        
 'A104-BG150-HT'  | '15PF'    | '5%'         = 'SMC_0201R'                | '(SMC_0201R_C)'                                 | 'CAP,15PF,5%50V,C0G,0201'                                                         | ''        
 'A104-DC682-HT'  | '6800PF'  | '10%'        = 'SMC_0201R'                | '(SMC_0201R_C)'                                 | 'CAP,6800PF,10%,25V,X7R,0201'                                                     | ''        
 'A104-KI333-HT'  | '0.033UF' | '10%'        = 'SMC_0201R'                | '(SMC_0201R_C)'                                 | 'CAP,0.033UF,10%,6.3V,X6S,0201'                                                   | ''        
 'A104-KJ683-HT'  | '0.068UF' | '20%'        = 'SMC_0201R'                | '(SMC_0201R_C)'                                 | 'CAP,0.068UF,20%,6.3V,X6S,0201'                                                   | ''        
 'A105-CI474-HT'  | '0.47UF'  | '10%'        = 'SMC_0402R_H022'           | '(SMC_0402R_C_H022)'                            | 'CAP,0.47UF,10%,6.3V,X7R,0402'                                                    | ''        
 'A105-KO225-HT'  | '2.2UF'   | '20%'        = 'SMC_0402R_H024'           | '(SMC_0402R_C_H024)'                            | 'CAP,2.2UF,20%,10V,X6S,0402'                                                      | ''        
 'A105-KJ475-HT'  | '4.7UF'   | '20%'        = 'SMC_0402R_H026'           | '(SMC_0402R_C_H026)'                            | 'CAP,4.7UF,20%,6.3V,X6S,0402'                                                     | ''        
 'A106-KE226-HT'  | '22UF'    | '20%'        = 'SMC_0603R_H039'           | '(SMC_0603R_H039)'                              | 'CAP,22UF,20%,4V,X6S,0603'                                                        | ''        
 'A107-KE476-HT'  | '47UF'    | '20%'        = 'SMC_0805R_H057'           | '(SMC_0805R_H057)'                              | 'CAP,47UF,20%,4V,X6S,0805'                                                        | ''        
 'A104-DC332-HT'  | '3300PF'  | '10%'        = 'SMC_0201R'                | '(SMC_0201R_C)'                                 | 'CAP,3300PF,10%,25V,X7R,0201'                                                     | ''        
 'A106-KE106-HT'  | '10UF'    | '20%'        = 'SMC_0603R_H037'           | '(SMC_0603R_H037)'                              | 'CAP,10UF,20%,4V,X6S,0603'                                                        | ''        
 'G104-0A150-FJ'  | '15PF'    | '5%'         = 'SMC_0201R'                | '(SMC_0201R_C)'                                 | 'CAP,15PF,5%,50V,C0G,0201'                                                        | ''        
 'A105-1B103-HT'  | '0.01UF'  | '10%'        = 'SMC_0402R_H022'           | '(SMC_0402R_C_H022)'                            | 'CAP,0.01UF,10%,16V,X7R,0402'                                                     | ''        
 'A105-2B103-HT'  | '0.01UF'  | '20%'        = 'SMC_0402R_H022'           | '(SMC_0402R_C_H022)'                            | 'CAP,0.01UF,20%,16V,X7R,0402'                                                     | ''        
 'A105-1B222-HT'  | '2200PF'  | '10%'        = 'SMC_0402R_H022'           | '(SMC_0402R_C_H022)'                            | 'CAP,2200PF,10%,50V,X7R,0402'                                                     | ''        
 'A108-0C226-HT'  | '22UF'    | '20%'        = 'SMC_1206R_H075'           | '(SMC_1206R_H075)'                              | 'CAP,22UF,20%,25V,X5R,1206'                                                       | ''        
 'A107-1C106-HT'  | '10UF'    | '10%'        = 'SMC_0805R_H057'           | '(SMC_0805R_H057)'                              | 'CAP,10UF,10%,10V,X5R,0805'                                                       | ''        
 'A107-0B105-HT'  | '1UF'     | '10%'        = 'SMC_0805R_H057'           | '(SMC_0805R_H057)'                              | 'CAP,1UF,10%,25V,X7R,0805'                                                        | ''        
 'A107-0B475-HT'  | '4.7UF'   | '10%'        = 'SMC_0805R_H055'           | '(SMC_0805R_H055)'                              | 'CAP,4.7UF,10%,16V,X7R,0805'                                                      | ''        
 'A106-0B103-HT'  | '0.01UF'  | '10%'        = 'SMC_0603R_H035'           | '(SMC_0603R_H035)'                              | 'CAP,0.01UF,10%,50V,X7R,0603'                                                     | 'REJECTED'
 'A109-0C226-HT'  | '22UF'    | '20%'        = 'SMC_C_1210_100THK'        | '(SMC_C_1210_100THK)'                           | 'CAP,22UF,20%,25V,X5R,1210'                                                       | ''        
 'A106-0B224-HT'  | '0.22UF'  | '10%'        = 'SMC_0603R'                | '(SMC_0603R)'                                   | 'CAP,0.22UF,10%,16V,X7R,0603'                                                     | ''        
 'A101-10078-HT'  | '100UF'   | '20%'        = 'SMC_0805R_H057'           | '(SMC_0805R_H057)'                              | 'CAP,100UF,20%,2.5V,X5R,0805'                                                     | ''        
 'A104-0C103-HT'  | '0.01UF'  | '10%'        = 'SMC_0201R'                | '(SMC_0201R_C)'                                 | 'CAP,0.01UF,10%,10V,X5R,0201'                                                     | ''        
 'A104-0B682-HT'  | '6800PF'  | '10%'        = 'SMC_0201R'                | '(SMC_0201R_C)'                                 | 'CAP,6800PF,10%,10V,X7R,0201'                                                     | ''        
 'A104-0B331-HT'  | '330PF'   | '10%'        = 'SMC_0201R'                | '(SMC_0201R_C)'                                 | 'CAP,330PF,10%,25V,X7R,0201'                                                      | ''        
 'A104-0B332-HT'  | '3300PF'  | '10%'        = 'SMC_0201R'                | '(SMC_0201R_C)'                                 | 'CAP,3300PF,10%,10V,X7R,0201'                                                     | ''        
 'A104-0B102-HT'  | '1000PF'  | '10%'        = 'SMC_0201R'                | '(SMC_0201R_C)'                                 | 'CAP,1000PF,10%,25V,X7R,0201'                                                     | ''        
 'A104-0B101-HT'  | '100PF'   | '5%'         = 'SMC_0201R'                | '(SMC_0201R_C)'                                 | 'CAP,100PF,5%,50V,X7R,0201'                                                       | ''        
 'A105-0B472-HT'  | '4700PF'  | '10%'        = 'SMC_0402R_H022'           | '(SMC_0402R_C_H022)'                            | 'CAP,4700PF,10%,25V,X7R,0402'                                                     | ''        
 'A105-0B182-HT'  | '1800PF'  | '10%'        = 'SMC_0402R_H022'           | '(SMC_0402R_C_H022)'                            | 'CAP,1800PF,10%,50V,X7R,0402'                                                     | ''        
 'A105-0A680-HT'  | '68PF'    | '5%'         = 'SMC_0402R_H022'           | '(SMC_0402R_C_H022)'                            | 'CAP,68PF,5%,50V,C0G,0402'                                                        | ''        
 'A105-0A331-HT'  | '330PF'   | '5%'         = 'SMC_0402R_H022'           | '(SMC_0402R_C_H022)'                            | 'CAP,330PF,5%,50V,C0G,0402'                                                       | ''        
 'A105-0A181-HT'  | '180PF'   | '5%'         = 'SMC_0402R_H022'           | '(SMC_0402R_C_H022)'                            | 'CAP,180PF,5%,50V,C0G,0402'                                                       | ''        
 'A104-0C474-HT'  | '0.47UF'  | '10%'        = 'SMC_0201R'                | '(SMC_0201R_C)'                                 | 'CAP,0.47UF,10%,6.3V,X5R,0201'                                                    | ''        
 'A104-0C333-HT'  | '0.033UF' | '10%'        = 'SMC_0201R'                | '(SMC_0201R_C)'                                 | 'CAP,0.033UF,10%,6.3V,X5R,0201'                                                   | ''        
 'A105-0B562-HT'  | '5600PF'  | '10%'        = 'SMC_0402R_H022'           | '(SMC_0402R_C_H022)'                            | 'CAP,5600PF,10%,50V,X7R,0402'                                                     | ''        
 'A105-0B822-HT'  | '8200PF'  | '10%'        = 'SMC_0402R_H022'           | '(SMC_0402R_C_H022)'                            | 'CAP,8200PF,10%,25V,X7R,0402'                                                     | ''        
 'A105-0C225-HT'  | '2.2UF'   | '20%'        = 'SMC_0402R_H022'           | '(SMC_0402R_C_H022)'                            | 'CAP,2.2UF,20%,6.3V,X5R,0402'                                                     | ''        
 'A106-0C475-HT'  | '4.7UF'   | '10%'        = 'SMC_0603R_H035'           | '(SMC_0603R_H035)'                              | 'CAP,4.7UF,10%,6.3V,X5R,0603'                                                     | ''        
 'A109-20020-DL'  | '220UF'   | '20%'        = 'SMC_1210R_H110'           | '(SMC_1210R_H110)'                              | 'CAP, 220UF, 20%, 6.3V, X5R, 1210'                                                | ''        
 'A108-20013-DL'  | '1000PF'  | '10%'        = 'SMC_1206R_H071'           | '(SMC_1206R_H071)'                              | 'CAP,1000PF,10%,2KVDC,X7R,1206'                                                   | ''        
 'G105-0C106-AM'  | '10UF'    | '20%'        = 'SMC_0402R_H028'           | '(SMC_0402R_C_H028)'                            | 'CAP,10UF,20%,4V,X5R,0402'                                                        | ''        
 'G104-0A270-FJ'  | '27PF'    | '5%'         = 'SMC_0201R'                | '(SMC_0201R_C)'                                 | 'CAP,27PF,5%,50V,C0G,0201'                                                        | ''        
 'G105-0F105-EK'  | '1UF'     | '10%'        = 'SMC_0402R_H024'           | '(SMC_0402R_C_H024)'                            | 'CAP,1UF,10%,25V,X6S,0402'                                                        | ''        
 'G104-0B472-EK'  | '4700PF'  | '10%'        = 'SMC_0201R'                | '(SMC_0201R_C)'                                 | 'CAP,4700PF,10%,25V,X7R,0201'                                                     | ''        
 'G104-0B471-FK'  | '470PF'   | '10%'        = 'SMC_0201R'                | '(SMC_0201R_C)'                                 | 'CAP,470PF,10%,50V,X7R,,0201'                                                     | ''        
 'G104-0B221-FK'  | '220PF'   | '10%'        = 'SMC_0201R'                | '(SMC_0201R_C)'                                 | 'CAP,220PF,10%,50V,X7R,0201'                                                      | ''        
 'G106-0C226-CM'  | '22UF'    | '20%'        = 'SMC_0603R_H039'           | '(SMC_0603R_H039)'                              | 'CAP,22UF,20%,10V,X5R,0603'                                                       | ''        
 'G107-0C226-EM'  | '22UF'    | '20%'        = 'SMC_0805R_H057'           | '(SMC_0805R_H057)'                              | 'CAP,22UF,20%,25V,X5R,0805'                                                       | ''        
 'G105-0B223-EK'  | '0.022UF' | '10%'        = 'SMC_0402R_H022'           | '(SMC_0402R_C_H022)'                            | 'CAP,0.022UF,10%,25V,X7R,0402'                                                    | ''        
 'G109-0F476-DM'  | '47UF'    | '20%'        = 'SMC_1210R_H110'           | '(SMC_1210R_H110)'                              | 'CAP, 47UF, 20%, 16V, X6S, 1210'                                                  | ''        
 'G109-0G107-BM'  | '100UF'   | '20%'        = 'SMC_1210R_H110'           | '(SMC_1210R_H110)'                              | 'CAP,100UF,20%,6.3V,X7S,1210'                                                     | ''        
 'G104-0A020-FC'  | '2PF'     | '0.25PF'     = 'SMC_0201R'                | '(SMC_0201R_C)'                                 | 'CAP,2PF,?.25PF,50V,C0G,0201'                                                     | ''        
 'G101-10037-01'  | '10UF'    | '10%'        = 'SMC_1210R_H110'           | '(SMC_1210R_H110)'                              | 'CAP,10UF,10%,50V,X7R,1210'                                                       | 'NFND'    
 'G107-0B473-EJ'  | '0.047UF' | '5%'         = 'SMC_0805R_H037'           | '(SMC_0805R_H037)'                              | 'CAP,0.047UF,5%,25V,X7R,0805'                                                     | 'NFND'    
 'G106-0B224-DK'  | '0.22UF'  | '10%'        = 'SMC_0603R_H035'           | '(SMC_0603R_H035)'                              | 'CAP,0.22UF,10%,16V,X7R,0603'                                                     | 'NFND'    
 'G105-0B104-EM'  | '0.1UF'   | '20%'        = 'SMC_0402R_H022'           | '(SMC_0402R_C_H022)'                            | 'CAP,0.1UF,20%,25V,X7R,0402'                                                      | ''        
 'R1141-T0001-01' | '10UF'    | '20%'        = 'SMC_0603R_H039'           | '(SMC_0603R_H039)'                              | 'ONLY SILVERSTONE 400G EVT USE'                                                   | ''        
 'A105-00001-AL'  | '47PF'    | '5%'         = 'SMC_0402R_H022'           | '(SMC_0402R_C_H022)'                            | 'CAP,47PF,5%,50V,C0G,0402'                                                        | ''        
 'G104-0A6R0-FB'  | '6PF'     | '0.1PF'      = 'SMC_0201R'                | '(SMC_0201R)'                                   | 'CAP,6PF,±0.1PF,50V,C0G,0201'                                                    | ''        
 'G104-0A680-FJ'  | '68PF'    | '5%'         = 'SMC_0201R'                | '(SMC_0201R_C)'                                 | 'CAP,68PF,+-5%,50V,COG,-55 TO +125°C,0201'                                       | ''        
 'G105-0A561-FJ'  | '560PF'   | '5%'         = 'SMC_0402R_H022'           | '(SMC_0402R_C_H022)'                            | 'CAP,560PF,5%,50V,C0G,0402'                                                       | 'NFND'    
 'G101-10110-01'  | '1000PF'  | '10%'        = 'SMC_0603R_H037'           | '(SMC_0603R_H037)'                              | 'CAP,1000PF,±10%,50V,X7R,0603,FLEX'                                              | ''        
 'G101-10111-01'  | '0.1UF'   | '10%'        = 'SMC_0603R_H039'           | '(SMC_0603R_H039)'                              | 'CAP,0.1UF,±10%,25V,X7R,0603,FLEX'                                               | ''        
 'G101-10112-01'  | '0.22UF'  | '10%'        = 'SMC_0603R_H039'           | '(SMC_0603R_H039)'                              | 'CAP,0.22UF,±10%,25V,X7R,0603,FLEX'                                              | ''        
 'G105-0B152-FK'  | '1500PF'  | '10%'        = 'SMC_0402R_H022'           | '(SMC_0402R_C_H022)'                            | 'CAP,1500PF,10%,50V,X7R,0402'                                                     | ''        
 'A104-0C475-FB'  | '4.7UF'   | '20%'        = 'SMC_0201R_H022'           | '(SMC_0201R_C_H022)'                            | 'CAP,4.7UF,20%,6.3V,X5R,0201'                                                     | ''        
 'G101-10113-01'  | '47UF'    | '20%'        = 'SMC_0603R_H039'           | '(SMC_0603R_H039)'                              | 'CAP,47UF,20%,2.5V,X6S,0603'                                                      | ''        
 'A107-0B102-FB'  | '1000PF'  | '10%'        = 'SMC_0805R_H057'           | '(SMC_0805R_H057)'                              | 'CAP,1000PF,±10%,100V,X7R,0805,FAIL SAFE'                                        | ''        
 'A107-0B332-FB'  | '3300PF'  | '10%'        = 'SMC_0805R_H057'           | '(SMC_0805R_H057)'                              | 'CAP,3300PF,±10%,100V,X7R,0805,FAIL SAFE'                                        | ''        
 'G105-0B473-FK'  | '0.047UF' | '10%'        = 'SMC_0402R_H022'           | '(SMC_0402R_C_H022)'                            | 'CAP,0.047UF,10%,X7R,50V,0402'                                                    | ''        
 'G104-0A8R2-FJ'  | '8.2PF'   | '5%'         = 'SMC_0201R'                | '(SMC_0201R_C)'                                 | 'CAP,8.2PF,5%,50V,C0G,0201'                                                       | 'REJECTED'
 'G104-0A8R2-FD'  | '8.2PF'   | '5%'         = 'SMC_0201R'                | '(SMC_0201R_C)'                                 | 'CAP,8.2PF,+/-0.5PF,50V,C0G,0201'                                                 | ''        
 'G104-0B223-DK'  | '0.022UF' | '10%'        = 'SMC_0201R'                | '(SMC_0201R_C)'                                 | 'CAP,0.022UF,10%,16V,X7R,0201'                                                    | ''        
 'G105-0F106-AM'  | '10UF'    | '20%'        = 'SMC_0402R_H028'           | '(SMC_0402R_C_H028,C0402_BGA,C0402-0P8MM-45DG,C0402-P8MM-S0,C0402-1MM-TRIANGLE-S0)'                  | 'CAP,10UF,20%,4V,X6S,0402'                                                        | ''        
 'G101-10114-01'  | '2200PF'  | '10%'        = 'SMC_2220R_V1_H0591'       | '(SMC_2220R_V1_H0591)'                          | 'CAP,2200PF,10%,AC250V,X7R,2220'                                                  | ''        
 'G104-0A560-FJ'  | '56PF'    | '5%'         = 'SMC_0201R'                | '(SMC_0201R_C)'                                 | 'CAP,56PF,5%,50V,C0G,0201'                                                        | ''        
 'G104-0A010-FK'  | '1PF'     | '5%'         = 'SMC_0201R'                | '(SMC_0201R_C)'                                 | 'CAP,1PF,±5%,50V,C0G,0201'                                                       | ''        
 'G105-0B472-FK'  | '4700PF'  | '10%'        = 'SMC_0402R_H026'           | '(SMC_0402R_C_H026)'                            | 'CAP,4700PF,10%,50V,X7R,0402'                                                     | ''        
 'G105-0B332-FK'  | '3300PF'  | '10%'        = 'SMC_0402R_H022'           | '(SMC_0402R_C_H022)'                            | 'CAP,3300PF,10%,50V,X7R,0402'                                                     | 'NFND'    
 'G106-0C106-EM'  | '10UF'    | '20%'        = 'SMC_0603R_H039'           | '(SMC_0603R_H039)'                              | 'CAP,10UF,20%,25V,X5R,0603'                                                       | ''        
 'G106-0C106-BK'  | '10UF'    | '10%'        = 'SMC_0603R_H037'           | '(SMC_0603R_H037)'                              | 'CAP,10UF,10%,6.3V,X5R,0603'                                                      | ''        
 'G105-0B151-FK'  | '150PF'   | '10%'        = 'SMC_0402R_H022'           | '(SMC_0402R_C_H022)'                            | 'CAP,150PF,10%,50V,X7R,0402'                                                      | ''        
 'G106-0B103-DK'  | '0.01UF'  | '10%'        = 'SMC_0603R_H035'           | '(SMC_0603R_H035)'                              | 'CAP,0.01UF,10%,16V,X7R,0603'                                                     | ''        
 'G105-0C474-EK'  | '0.47UF'  | '10%'        = 'SMC_0402R_H024'           | '(SMC_0402R_C_H024)'                            | 'CAP,0.47UF,10%,25V,X5R,0402'                                                     | ''        
 'G105-0B221-FK'  | '220PF'   | '10%'        = 'SMC_0402R_H026'           | '(SMC_0402R_C_H026)'                            | 'CAP,220PF,10%,50V,X7R,0402'                                                      | ''        
 'G106-0F475-DK'  | '4.7UF'   | '10%'        = 'SMC_0603R_H037'           | '(SMC_0603R_H037)'                              | 'CAP,4.7UF,10%,16V,X6S,0603'                                                      | ''        
 'G104-0A100-FJ'  | '10PF'    | '5%'         = 'SMC_0201R'                | '(SMC_0201R_C)'                                 | 'CAP,10PF,5%,50V,C0G,0201'                                                        | ''        
 'G104-0B681-FK'  | '680PF'   | '10%'        = 'SMC_0201R'                | '(SMC_0201R_C)'                                 | 'CAP,680PF,10%,50V,X7R,0201'                                                      | ''        
 'G107-0B475-EK'  | '4.7UF'   | '10%'        = 'SMC_0805R_H053'           | '(SMC_0805R_H053)'                              | 'CAP,4.7UF,10%,25V,X7R,CER,0805'                                                  | ''        
 'G106-0B474-DK'  | '0.47UF'  | '10%'        = 'SMC_0603R_H035'           | '(SMC_0603R_H035)'                              | 'CAP,0.47UF,10%,16V,X7R,0603'                                                     | ''        
 'G105-0B473-EK'  | '0.047UF' | '10%'        = 'SMC_0402R_H022'           | '(SMC_0402R_C_H022)'                            | 'CAP,0.047UF,10%,25V,X7R,0402'                                                    | ''        
 'G105-0C475-CM'  | '4.7UF'   | '20%'        = 'SMC_0402R_H026'           | '(SMC_0402R_C_H026)'                            | 'CAP,4.7UF,20%,10V,X5R,0402'                                                      | ''        
 'G109-0C107-DM'  | '100UF'   | '20%'        = 'SMC_1210R_H106'           | '(SMC_1210R_H106)'                              | 'CAP,MLCC,100UF,+/-20%,16V,X5R,SMD1210'                                           | ''        
 'G105-0F226-AM'  | '22UF'    | '20%'        = 'SMC_0402R_H031'           | '(SMC_0402R_C_H031,C0402_BGA)'                  | 'CAP,22UF,20%,4V,X6S,0402'                                                        | '' 
 'G101-10116-01'  | '0.1UF'   | '10%'        = 'SMC_1210R_H091'           | '(SMC_1210R_H091)'                              | 'CAP,0.1UF,10%,500V,X7R,1210'                                                     | ''   
 'G105-0A102-FJ'  | '1000PF'  | '5%'         = 'SMC_0402R_H022'           | '(SMC_0402R_C_H022,SMC_0402R_V2_H022,C0402-1MM-TRIANGLE-S0,C0402-P8MM-S0)'          | 'CAP,1000PF,5%,50V,C0G,0402'                                                      | ''    
 'A104-0F474-IB'  | '0.47UF'  | '10%'        = 'SMC_0201R_H015'           | '(SMC_0201R_C_H015)'                            | 'CAP,0.47UF,10%,6.3V,X6S,0201'                                                    | ''    
 'G105-0A1R5-FB'  | '1.5PF'   | '0.1%'       = 'SMC_0402R_H022'           | '(SMC_0402R_C_H022)'                            | 'CAP,1.5PF,0.1%,50V,NPO,0402'                                                     | ''    
 'G108-0C227-BM'  | '220UF'   | '20%'        = 'SMC_1206R_H075'           | '(SMC_1206R_H075)'                              | 'CAP,220UF,20%,6.3V,X5R,1206'                                                     | ''    
 'G105-0F225-01'  | '2.2UF'   | '20%'        = 'SMC_0402R_H028'           | '(SMC_0402R_C_H028)'                            | 'CAP,2.2UF,20%,10V,X6S,0402'                                                      | ''        
 'G105-0C683-CK'  | '68000PF' | '10%'        = 'SMC_0402R_H022'           | '(SMC_0402R_C_H022)'                            | 'CAP,68000PF,10%,10V,X5R,0402'                                                    | ''        
 'A105-0C226-AW'  | '22UF'    | '20%'        = 'SMC_0402R_H031'           | '(SMC_0402R_C_H031)'                            | 'CAP,22UF,20%,10V,X5R,0402'                                                       | '' 
 'A106-1F106-HT'  | '10UF'    | '20%'        = 'SMC_0603R_H039'           | '(SMC_0603R_H039)'                              | 'CAP,10UF,20%,10V,X6S,0603'                                                       | ''        
 'A108-1C226-HT'  | '22UF'    | '20%'        = 'SMC_1206R_H075'           | '(SMC_1206R_H075)'                              | 'CAP,22UF,20%,25V,X5R,1206'                                                       | ''        

END_PART

END.

